G04 ================== begin FILE IDENTIFICATION RECORD ==================*
G04 Layout Name:  15105-sa.brd*
G04 Film Name:    DP_REF_L1*
G04 File Format:  Gerber RS274X*
G04 File Origin:  Cadence Allegro 16.5-S056*
G04 Origin Date:  Wed Nov 16 02:02:32 2016*
G04 *
G04 Layer:  BOARD GEOMETRY/DP_REF_L1_TBL*
G04 Layer:  BOARD GEOMETRY/DP_REF_L1_TOP*
G04 Layer:  BOARD GEOMETRY/PANEL_OUTLINE*
G04 *
G04 Offset:    (0.00 0.00)*
G04 Mirror:    No*
G04 Mode:      Positive*
G04 Rotation:  0*
G04 FullContactRelief:  No*
G04 UndefLineWidth:     6.00*
G04 ================== end FILE IDENTIFICATION RECORD ====================*
%FSLAX35Y35*MOIN*%
%IR0*IPPOS*OFA0.00000B0.00000*MIA0B0*SFA1.00000B1.00000*%
%ADD10C,.02*%
%ADD11C,.006*%
%ADD12C,.00413*%
%ADD13C,.00538*%
G75*
%LPD*%
G75*
G54D10*
G01X1479970Y759338D02*
X2249970D01*
G01X1479970Y863288D02*
Y759338D01*
G01Y793988D02*
X2249970D01*
G01X1479970Y828638D02*
X2249970D01*
G01X1479970Y863288D02*
X2249970D01*
G01X1654970D02*
Y759338D01*
G01X1934970Y863288D02*
Y759338D01*
G01X2039970Y863288D02*
Y759338D01*
G01X2249970Y863288D02*
Y759338D01*
G54D11*
G01X-27072Y-83981D02*
Y-101481D01*
G01X-32094Y-83981D02*
X-22050D01*
G01X-13284Y-101481D02*
Y-83981D01*
G01Y-92439D02*
X-12192Y-90981D01*
X-11100Y-90106D01*
X-9354Y-89815D01*
X-8044Y-90106D01*
X-6515Y-91273D01*
X-5860Y-93023D01*
Y-101481D01*
G01X7928Y-89815D02*
Y-101481D01*
G01Y-85148D02*
X7491Y-84856D01*
Y-84273D01*
X7928Y-83981D01*
X8365Y-84273D01*
Y-84856D01*
X7928Y-85148D01*
G01X22153Y-99440D02*
X23245Y-100606D01*
X24773Y-101481D01*
X26083D01*
X27393Y-100898D01*
X28266Y-100023D01*
X28703Y-98857D01*
X28485Y-97106D01*
X27611Y-96231D01*
X23681Y-94481D01*
X22808Y-92439D01*
X23245Y-90981D01*
X24118Y-90106D01*
X25428Y-89815D01*
X26738Y-90106D01*
X28048Y-90981D01*
G01X57371Y-105856D02*
X58900Y-107023D01*
X60646Y-107314D01*
X62174Y-107023D01*
X63485Y-105565D01*
X64358Y-103523D01*
Y-89815D01*
G01Y-92148D02*
X63485Y-90981D01*
X62174Y-90106D01*
X60646Y-89815D01*
X58900Y-90398D01*
X57808Y-91564D01*
X56934Y-93606D01*
X56498Y-95648D01*
X56716Y-97398D01*
X57590Y-99440D01*
X58900Y-100898D01*
X60646Y-101481D01*
X61956Y-101189D01*
X63485Y-100023D01*
X64358Y-98857D01*
G01X74653Y-93606D02*
X81640D01*
X80985Y-91564D01*
X79893Y-90398D01*
X78365Y-89815D01*
X76836Y-90106D01*
X75526Y-90981D01*
X74653Y-93023D01*
X74216Y-94773D01*
Y-96523D01*
X74653Y-98273D01*
X75745Y-100023D01*
X77055Y-101189D01*
X78583Y-101481D01*
X80111Y-100898D01*
X81640Y-99148D01*
G01X92371Y-101481D02*
Y-89815D01*
G01Y-92148D02*
X93463Y-90981D01*
X94555Y-90106D01*
X96083Y-89815D01*
X97174Y-90106D01*
X98485Y-90981D01*
G01X108998Y-101481D02*
Y-83981D01*
G01Y-92731D02*
X110090Y-90981D01*
X111400Y-90106D01*
X112710Y-89815D01*
X114674Y-90398D01*
X115985Y-91564D01*
X116858Y-93606D01*
Y-95939D01*
X116421Y-98273D01*
X115548Y-100023D01*
X114020Y-101189D01*
X112710Y-101481D01*
X111400Y-101189D01*
X110090Y-100315D01*
X108998Y-98857D01*
G01X127153Y-93606D02*
X134140D01*
X133485Y-91564D01*
X132393Y-90398D01*
X130865Y-89815D01*
X129336Y-90106D01*
X128026Y-90981D01*
X127153Y-93023D01*
X126716Y-94773D01*
Y-96523D01*
X127153Y-98273D01*
X128245Y-100023D01*
X129555Y-101189D01*
X131083Y-101481D01*
X132611Y-100898D01*
X134140Y-99148D01*
G01X144871Y-101481D02*
Y-89815D01*
G01Y-92148D02*
X145963Y-90981D01*
X147055Y-90106D01*
X148583Y-89815D01*
X149674Y-90106D01*
X150985Y-90981D01*
G01X182928Y-89815D02*
Y-101481D01*
G01Y-85148D02*
X182491Y-84856D01*
Y-84273D01*
X182928Y-83981D01*
X183365Y-84273D01*
Y-84856D01*
X182928Y-85148D01*
G01X197153Y-99440D02*
X198245Y-100606D01*
X199773Y-101481D01*
X201083D01*
X202393Y-100898D01*
X203266Y-100023D01*
X203703Y-98857D01*
X203485Y-97106D01*
X202611Y-96231D01*
X198681Y-94481D01*
X197808Y-92439D01*
X198245Y-90981D01*
X199118Y-90106D01*
X200428Y-89815D01*
X201738Y-90106D01*
X203048Y-90981D01*
G01X231934Y-105856D02*
X233463Y-107023D01*
X234773Y-107314D01*
X236520Y-106731D01*
X237830Y-105273D01*
X238485Y-102647D01*
Y-89815D01*
G01Y-85148D02*
X238048Y-84856D01*
Y-84273D01*
X238485Y-83981D01*
X238921Y-84273D01*
Y-84856D01*
X238485Y-85148D01*
G01X249216Y-89815D02*
Y-97981D01*
X250090Y-100023D01*
X251400Y-101189D01*
X252928Y-101481D01*
X254456Y-101189D01*
X255766Y-100023D01*
X256640Y-97981D01*
G01Y-101481D02*
Y-89815D01*
G01X267153Y-99440D02*
X268245Y-100606D01*
X269773Y-101481D01*
X271083D01*
X272393Y-100898D01*
X273266Y-100023D01*
X273703Y-98857D01*
X273485Y-97106D01*
X272611Y-96231D01*
X268681Y-94481D01*
X267808Y-92439D01*
X268245Y-90981D01*
X269118Y-90106D01*
X270428Y-89815D01*
X271738Y-90106D01*
X273048Y-90981D01*
G01X287928Y-83981D02*
Y-101481D01*
G01X284871Y-89815D02*
X290985D01*
G01X321618Y-101481D02*
Y-86606D01*
X322055Y-85148D01*
X322928Y-84273D01*
X324238Y-83981D01*
X325548Y-84564D01*
X326203Y-86023D01*
G01X323583Y-90981D02*
X319216D01*
G01X340428Y-101481D02*
X339118Y-101189D01*
X337808Y-100023D01*
X336934Y-97981D01*
X336498Y-95648D01*
X336934Y-93314D01*
X337808Y-91273D01*
X339118Y-90106D01*
X340428Y-89815D01*
X341738Y-90106D01*
X343048Y-91273D01*
X343921Y-93314D01*
X344140Y-95648D01*
X343921Y-97981D01*
X343048Y-100023D01*
X341738Y-101189D01*
X340428Y-101481D01*
G01X354871D02*
Y-89815D01*
G01Y-92148D02*
X355963Y-90981D01*
X357055Y-90106D01*
X358583Y-89815D01*
X359674Y-90106D01*
X360985Y-90981D01*
G01X388343Y-106731D02*
X389653Y-107314D01*
X391400Y-106731D01*
X392491Y-105565D01*
X393365Y-104106D01*
X394674Y-99440D01*
X397513Y-89815D01*
G01X390526D02*
X394674Y-99440D01*
G01X410428Y-101481D02*
X409118Y-101189D01*
X407808Y-100023D01*
X406934Y-97981D01*
X406498Y-95648D01*
X406934Y-93314D01*
X407808Y-91273D01*
X409118Y-90106D01*
X410428Y-89815D01*
X411738Y-90106D01*
X413048Y-91273D01*
X413921Y-93314D01*
X414140Y-95648D01*
X413921Y-97981D01*
X413048Y-100023D01*
X411738Y-101189D01*
X410428Y-101481D01*
G01X424216Y-89815D02*
Y-97981D01*
X425090Y-100023D01*
X426400Y-101189D01*
X427928Y-101481D01*
X429456Y-101189D01*
X430766Y-100023D01*
X431640Y-97981D01*
G01Y-101481D02*
Y-89815D01*
G01X442371Y-101481D02*
Y-89815D01*
G01Y-92148D02*
X443463Y-90981D01*
X444555Y-90106D01*
X446083Y-89815D01*
X447174Y-90106D01*
X448485Y-90981D01*
G01X477371Y-101481D02*
Y-89815D01*
G01Y-92148D02*
X478463Y-90981D01*
X479555Y-90106D01*
X481083Y-89815D01*
X482174Y-90106D01*
X483485Y-90981D01*
G01X494653Y-93606D02*
X501640D01*
X500985Y-91564D01*
X499893Y-90398D01*
X498365Y-89815D01*
X496836Y-90106D01*
X495526Y-90981D01*
X494653Y-93023D01*
X494216Y-94773D01*
Y-96523D01*
X494653Y-98273D01*
X495745Y-100023D01*
X497055Y-101189D01*
X498583Y-101481D01*
X500111Y-100898D01*
X501640Y-99148D01*
G01X514118Y-101481D02*
Y-86606D01*
X514555Y-85148D01*
X515428Y-84273D01*
X516738Y-83981D01*
X518048Y-84564D01*
X518703Y-86023D01*
G01X516083Y-90981D02*
X511716D01*
G01X529653Y-93606D02*
X536640D01*
X535985Y-91564D01*
X534893Y-90398D01*
X533365Y-89815D01*
X531836Y-90106D01*
X530526Y-90981D01*
X529653Y-93023D01*
X529216Y-94773D01*
Y-96523D01*
X529653Y-98273D01*
X530745Y-100023D01*
X532055Y-101189D01*
X533583Y-101481D01*
X535111Y-100898D01*
X536640Y-99148D01*
G01X547371Y-101481D02*
Y-89815D01*
G01Y-92148D02*
X548463Y-90981D01*
X549555Y-90106D01*
X551083Y-89815D01*
X552174Y-90106D01*
X553485Y-90981D01*
G01X564653Y-93606D02*
X571640D01*
X570985Y-91564D01*
X569893Y-90398D01*
X568365Y-89815D01*
X566836Y-90106D01*
X565526Y-90981D01*
X564653Y-93023D01*
X564216Y-94773D01*
Y-96523D01*
X564653Y-98273D01*
X565745Y-100023D01*
X567055Y-101189D01*
X568583Y-101481D01*
X570111Y-100898D01*
X571640Y-99148D01*
G01X581716Y-101481D02*
Y-89815D01*
G01Y-92731D02*
X582590Y-91273D01*
X583900Y-90106D01*
X585646Y-89815D01*
X587174Y-90106D01*
X588485Y-91273D01*
X589140Y-93314D01*
Y-101481D01*
G01X606421Y-91273D02*
X604893Y-90106D01*
X603583Y-89815D01*
X601836Y-90398D01*
X600526Y-91564D01*
X599653Y-93606D01*
X599434Y-95648D01*
X599653Y-97690D01*
X600526Y-99440D01*
X601836Y-100898D01*
X603583Y-101481D01*
X605111Y-100898D01*
X606421Y-99731D01*
G01X617153Y-93606D02*
X624140D01*
X623485Y-91564D01*
X622393Y-90398D01*
X620865Y-89815D01*
X619336Y-90106D01*
X618026Y-90981D01*
X617153Y-93023D01*
X616716Y-94773D01*
Y-96523D01*
X617153Y-98273D01*
X618245Y-100023D01*
X619555Y-101189D01*
X621083Y-101481D01*
X622611Y-100898D01*
X624140Y-99148D01*
G01X655428Y-83981D02*
Y-101481D01*
G01X652371Y-89815D02*
X658485D01*
G01X672928Y-101481D02*
X671618Y-101189D01*
X670308Y-100023D01*
X669434Y-97981D01*
X668998Y-95648D01*
X669434Y-93314D01*
X670308Y-91273D01*
X671618Y-90106D01*
X672928Y-89815D01*
X674238Y-90106D01*
X675548Y-91273D01*
X676421Y-93314D01*
X676640Y-95648D01*
X676421Y-97981D01*
X675548Y-100023D01*
X674238Y-101189D01*
X672928Y-101481D01*
G01X706618D02*
Y-86606D01*
X707055Y-85148D01*
X707928Y-84273D01*
X709238Y-83981D01*
X710548Y-84564D01*
X711203Y-86023D01*
G01X708583Y-90981D02*
X704216D01*
G01X725428Y-89815D02*
Y-101481D01*
G01Y-85148D02*
X724991Y-84856D01*
Y-84273D01*
X725428Y-83981D01*
X725865Y-84273D01*
Y-84856D01*
X725428Y-85148D01*
G01X739216Y-101481D02*
Y-89815D01*
G01Y-92731D02*
X740090Y-91273D01*
X741400Y-90106D01*
X743146Y-89815D01*
X744674Y-90106D01*
X745985Y-91273D01*
X746640Y-93314D01*
Y-101481D01*
G01X764358Y-83981D02*
Y-101481D01*
G01Y-98857D02*
X763485Y-100315D01*
X762174Y-101189D01*
X760646Y-101481D01*
X758900Y-100898D01*
X757590Y-99440D01*
X756716Y-97690D01*
X756498Y-95648D01*
X756716Y-93606D01*
X757590Y-91856D01*
X758900Y-90398D01*
X760646Y-89815D01*
X762174Y-90106D01*
X763266Y-90690D01*
X764358Y-91856D01*
G01X795428Y-83981D02*
Y-101481D01*
G01X792371Y-89815D02*
X798485D01*
G01X809216Y-101481D02*
Y-83981D01*
G01Y-92439D02*
X810308Y-90981D01*
X811400Y-90106D01*
X813146Y-89815D01*
X814456Y-90106D01*
X815985Y-91273D01*
X816640Y-93023D01*
Y-101481D01*
G01X827153Y-93606D02*
X834140D01*
X833485Y-91564D01*
X832393Y-90398D01*
X830865Y-89815D01*
X829336Y-90106D01*
X828026Y-90981D01*
X827153Y-93023D01*
X826716Y-94773D01*
Y-96523D01*
X827153Y-98273D01*
X828245Y-100023D01*
X829555Y-101189D01*
X831083Y-101481D01*
X832611Y-100898D01*
X834140Y-99148D01*
G01X860625Y-101481D02*
Y-83981D01*
X864991D01*
X866738Y-84856D01*
X868048Y-86023D01*
X869140Y-87772D01*
X870013Y-89815D01*
X870231Y-92731D01*
X870013Y-95648D01*
X869140Y-97690D01*
X868048Y-99440D01*
X866738Y-100606D01*
X864991Y-101481D01*
X860625D01*
G01X878561D02*
Y-83981D01*
X883801D01*
X885548Y-84856D01*
X886858Y-86898D01*
X887295Y-89231D01*
X886858Y-91564D01*
X885766Y-93314D01*
X883801Y-94190D01*
X878561D01*
G01X917928Y-89815D02*
Y-101481D01*
G01Y-85148D02*
X917491Y-84856D01*
Y-84273D01*
X917928Y-83981D01*
X918365Y-84273D01*
Y-84856D01*
X917928Y-85148D01*
G01X928878Y-101481D02*
Y-89815D01*
G01Y-93023D02*
X929533Y-91564D01*
X930625Y-90398D01*
X932153Y-89815D01*
X933681Y-90398D01*
X934773Y-91564D01*
X935428Y-93023D01*
Y-101481D01*
G01Y-93023D02*
X936083Y-91564D01*
X937174Y-90398D01*
X938703Y-89815D01*
X940231Y-90398D01*
X941323Y-91564D01*
X941978Y-93314D01*
Y-101481D01*
G01X948998Y-107314D02*
Y-89815D01*
G01Y-92439D02*
X950090Y-90981D01*
X951181Y-90106D01*
X952928Y-89815D01*
X954456Y-90106D01*
X955985Y-91564D01*
X956640Y-93606D01*
X956858Y-95648D01*
X956640Y-97690D01*
X955985Y-99731D01*
X954674Y-100898D01*
X952928Y-101481D01*
X951400Y-101189D01*
X949871Y-100315D01*
X948998Y-99148D01*
G01X967153Y-93606D02*
X974140D01*
X973485Y-91564D01*
X972393Y-90398D01*
X970865Y-89815D01*
X969336Y-90106D01*
X968026Y-90981D01*
X967153Y-93023D01*
X966716Y-94773D01*
Y-96523D01*
X967153Y-98273D01*
X968245Y-100023D01*
X969555Y-101189D01*
X971083Y-101481D01*
X972611Y-100898D01*
X974140Y-99148D01*
G01X991858Y-83981D02*
Y-101481D01*
G01Y-98857D02*
X990985Y-100315D01*
X989674Y-101189D01*
X988146Y-101481D01*
X986400Y-100898D01*
X985090Y-99440D01*
X984216Y-97690D01*
X983998Y-95648D01*
X984216Y-93606D01*
X985090Y-91856D01*
X986400Y-90398D01*
X988146Y-89815D01*
X989674Y-90106D01*
X990766Y-90690D01*
X991858Y-91856D01*
G01X1009358Y-101481D02*
Y-89815D01*
G01Y-91856D02*
X1008485Y-90690D01*
X1007174Y-90106D01*
X1005646Y-89815D01*
X1004118Y-90398D01*
X1002808Y-91564D01*
X1001934Y-93314D01*
X1001498Y-95648D01*
X1001934Y-97981D01*
X1002808Y-99731D01*
X1004118Y-100898D01*
X1005646Y-101481D01*
X1007174Y-101189D01*
X1008485Y-100315D01*
X1009358Y-99148D01*
G01X1019216Y-101481D02*
Y-89815D01*
G01Y-92731D02*
X1020090Y-91273D01*
X1021400Y-90106D01*
X1023146Y-89815D01*
X1024674Y-90106D01*
X1025985Y-91273D01*
X1026640Y-93314D01*
Y-101481D01*
G01X1043921Y-91273D02*
X1042393Y-90106D01*
X1041083Y-89815D01*
X1039336Y-90398D01*
X1038026Y-91564D01*
X1037153Y-93606D01*
X1036934Y-95648D01*
X1037153Y-97690D01*
X1038026Y-99440D01*
X1039336Y-100898D01*
X1041083Y-101481D01*
X1042611Y-100898D01*
X1043921Y-99731D01*
G01X1054653Y-93606D02*
X1061640D01*
X1060985Y-91564D01*
X1059893Y-90398D01*
X1058365Y-89815D01*
X1056836Y-90106D01*
X1055526Y-90981D01*
X1054653Y-93023D01*
X1054216Y-94773D01*
Y-96523D01*
X1054653Y-98273D01*
X1055745Y-100023D01*
X1057055Y-101189D01*
X1058583Y-101481D01*
X1060111Y-100898D01*
X1061640Y-99148D01*
G01X1092928Y-83981D02*
Y-101481D01*
G01X1089871Y-89815D02*
X1095985D01*
G01X1107371Y-101481D02*
Y-89815D01*
G01Y-92148D02*
X1108463Y-90981D01*
X1109555Y-90106D01*
X1111083Y-89815D01*
X1112174Y-90106D01*
X1113485Y-90981D01*
G01X1131858Y-101481D02*
Y-89815D01*
G01Y-91856D02*
X1130985Y-90690D01*
X1129674Y-90106D01*
X1128146Y-89815D01*
X1126618Y-90398D01*
X1125308Y-91564D01*
X1124434Y-93314D01*
X1123998Y-95648D01*
X1124434Y-97981D01*
X1125308Y-99731D01*
X1126618Y-100898D01*
X1128146Y-101481D01*
X1129674Y-101189D01*
X1130985Y-100315D01*
X1131858Y-99148D01*
G01X1148921Y-91273D02*
X1147393Y-90106D01*
X1146083Y-89815D01*
X1144336Y-90398D01*
X1143026Y-91564D01*
X1142153Y-93606D01*
X1141934Y-95648D01*
X1142153Y-97690D01*
X1143026Y-99440D01*
X1144336Y-100898D01*
X1146083Y-101481D01*
X1147611Y-100898D01*
X1148921Y-99731D01*
G01X1159653Y-93606D02*
X1166640D01*
X1165985Y-91564D01*
X1164893Y-90398D01*
X1163365Y-89815D01*
X1161836Y-90106D01*
X1160526Y-90981D01*
X1159653Y-93023D01*
X1159216Y-94773D01*
Y-96523D01*
X1159653Y-98273D01*
X1160745Y-100023D01*
X1162055Y-101189D01*
X1163583Y-101481D01*
X1165111Y-100898D01*
X1166640Y-99148D01*
G01X1177153Y-99440D02*
X1178245Y-100606D01*
X1179773Y-101481D01*
X1181083D01*
X1182393Y-100898D01*
X1183266Y-100023D01*
X1183703Y-98857D01*
X1183485Y-97106D01*
X1182611Y-96231D01*
X1178681Y-94481D01*
X1177808Y-92439D01*
X1178245Y-90981D01*
X1179118Y-90106D01*
X1180428Y-89815D01*
X1181738Y-90106D01*
X1183048Y-90981D01*
G01X1215428Y-89815D02*
Y-101481D01*
G01Y-85148D02*
X1214991Y-84856D01*
Y-84273D01*
X1215428Y-83981D01*
X1215865Y-84273D01*
Y-84856D01*
X1215428Y-85148D01*
G01X1229216Y-101481D02*
Y-89815D01*
G01Y-92731D02*
X1230090Y-91273D01*
X1231400Y-90106D01*
X1233146Y-89815D01*
X1234674Y-90106D01*
X1235985Y-91273D01*
X1236640Y-93314D01*
Y-101481D01*
G01X1267928D02*
Y-83981D01*
G01X1289358Y-101481D02*
Y-89815D01*
G01Y-91856D02*
X1288485Y-90690D01*
X1287174Y-90106D01*
X1285646Y-89815D01*
X1284118Y-90398D01*
X1282808Y-91564D01*
X1281934Y-93314D01*
X1281498Y-95648D01*
X1281934Y-97981D01*
X1282808Y-99731D01*
X1284118Y-100898D01*
X1285646Y-101481D01*
X1287174Y-101189D01*
X1288485Y-100315D01*
X1289358Y-99148D01*
G01X1298343Y-106731D02*
X1299653Y-107314D01*
X1301400Y-106731D01*
X1302491Y-105565D01*
X1303365Y-104106D01*
X1304674Y-99440D01*
X1307513Y-89815D01*
G01X1300526D02*
X1304674Y-99440D01*
G01X1317153Y-93606D02*
X1324140D01*
X1323485Y-91564D01*
X1322393Y-90398D01*
X1320865Y-89815D01*
X1319336Y-90106D01*
X1318026Y-90981D01*
X1317153Y-93023D01*
X1316716Y-94773D01*
Y-96523D01*
X1317153Y-98273D01*
X1318245Y-100023D01*
X1319555Y-101189D01*
X1321083Y-101481D01*
X1322611Y-100898D01*
X1324140Y-99148D01*
G01X1334871Y-101481D02*
Y-89815D01*
G01Y-92148D02*
X1335963Y-90981D01*
X1337055Y-90106D01*
X1338583Y-89815D01*
X1339674Y-90106D01*
X1340985Y-90981D01*
G01X1368561Y-83981D02*
Y-101481D01*
X1377295D01*
G01X1390428D02*
Y-83981D01*
X1387808Y-87481D01*
G01Y-101481D02*
X1393048D01*
G01X1407928Y-102064D02*
X1407491Y-101773D01*
Y-101189D01*
X1407928Y-100898D01*
X1408365Y-101189D01*
Y-101773D01*
X1407928Y-102064D01*
G01X1481717Y873038D02*
Y890538D01*
X1486083D01*
X1487830Y889663D01*
X1489140Y888496D01*
X1490232Y886747D01*
X1491105Y884704D01*
X1491323Y881788D01*
X1491105Y878871D01*
X1490232Y876829D01*
X1489140Y875079D01*
X1487830Y873913D01*
X1486083Y873038D01*
X1481717D01*
G01X1499653D02*
Y890538D01*
X1504893D01*
X1506640Y889663D01*
X1507950Y887621D01*
X1508387Y885288D01*
X1507950Y882955D01*
X1506858Y881205D01*
X1504893Y880329D01*
X1499653D01*
G01X1536400Y890538D02*
X1541640D01*
G01X1539020D02*
Y873038D01*
G01X1536400D02*
X1541640D01*
G01X1550843D02*
Y890538D01*
X1556520Y875955D01*
X1562197Y890538D01*
Y873038D01*
G01X1569653D02*
Y890538D01*
X1574893D01*
X1576640Y889663D01*
X1577950Y887621D01*
X1578387Y885288D01*
X1577950Y882955D01*
X1576858Y881205D01*
X1574893Y880329D01*
X1569653D01*
G01X1595887Y873038D02*
X1587153D01*
Y890538D01*
X1595887D01*
G01X1592393Y882080D02*
X1587153D01*
G01X1604217Y873038D02*
Y890538D01*
X1608583D01*
X1610330Y889663D01*
X1611640Y888496D01*
X1612732Y886747D01*
X1613605Y884704D01*
X1613823Y881788D01*
X1613605Y878871D01*
X1612732Y876829D01*
X1611640Y875079D01*
X1610330Y873913D01*
X1608583Y873038D01*
X1604217D01*
G01X1621061D02*
X1626520Y890538D01*
X1631979Y873038D01*
G01X1630013Y879163D02*
X1623026D01*
G01X1638998Y873038D02*
Y890538D01*
X1649042Y873038D01*
Y890538D01*
G01X1666323Y889079D02*
X1665013Y889955D01*
X1663485Y890538D01*
X1661738D01*
X1659773Y889663D01*
X1658245Y888205D01*
X1657153Y886454D01*
X1656280Y883538D01*
X1656061Y880913D01*
X1656498Y878288D01*
X1657153Y876538D01*
X1658463Y874788D01*
X1659992Y873621D01*
X1661520Y873038D01*
X1663048D01*
X1664577Y873621D01*
X1665887Y874496D01*
X1666979Y875662D01*
G01X1683387Y873038D02*
X1674653D01*
Y890538D01*
X1683387D01*
G01X1679893Y882080D02*
X1674653D01*
G01X1714020Y890538D02*
Y873038D01*
G01X1708998Y890538D02*
X1719042D01*
G01X1726061Y873038D02*
X1731520Y890538D01*
X1736979Y873038D01*
G01X1735013Y879163D02*
X1728026D01*
G01X1750766Y882371D02*
X1751640Y883246D01*
X1752295Y884704D01*
X1752732Y886747D01*
X1752295Y888496D01*
X1751422Y889663D01*
X1749893Y890538D01*
X1743998D01*
Y873038D01*
X1751203D01*
X1752732Y874204D01*
X1753605Y875955D01*
X1754042Y877996D01*
X1753605Y880038D01*
X1752295Y881788D01*
X1750766Y882371D01*
X1743998D01*
G01X1762153Y890538D02*
Y873038D01*
X1770887D01*
G01X1788387D02*
X1779653D01*
Y890538D01*
X1788387D01*
G01X1784893Y882080D02*
X1779653D01*
G01X1801520Y872455D02*
X1801083Y872746D01*
Y873330D01*
X1801520Y873621D01*
X1801957Y873330D01*
Y872746D01*
X1801520Y872455D01*
G01Y880329D02*
X1801083Y880621D01*
Y881205D01*
X1801520Y881496D01*
X1801957Y881205D01*
Y880621D01*
X1801520Y880329D01*
G01X1832153Y890538D02*
Y873038D01*
X1840887D01*
G01X1854020D02*
Y890538D01*
X1851400Y887038D01*
G01Y873038D02*
X1856640D01*
G01X1503600Y855888D02*
X1508840D01*
G01X1506220D02*
Y838388D01*
G01X1503600D02*
X1508840D01*
G01X1518043D02*
Y855888D01*
X1523720Y841305D01*
X1529397Y855888D01*
Y838388D01*
G01X1536853D02*
Y855888D01*
X1542093D01*
X1543840Y855013D01*
X1545150Y852971D01*
X1545587Y850638D01*
X1545150Y848305D01*
X1544058Y846555D01*
X1542093Y845679D01*
X1536853D01*
G01X1557628Y832555D02*
X1555445Y835471D01*
X1554353Y838388D01*
Y850054D01*
X1555445Y852971D01*
X1557628Y855888D01*
G01X1576220Y838388D02*
X1574473Y838680D01*
X1572945Y839846D01*
X1571635Y841596D01*
X1570761Y843638D01*
X1570325Y845971D01*
Y848305D01*
X1570761Y850638D01*
X1571635Y852680D01*
X1572945Y854429D01*
X1574473Y855596D01*
X1576220Y855888D01*
X1577966Y855596D01*
X1579495Y854429D01*
X1580805Y852680D01*
X1581679Y850638D01*
X1582115Y848305D01*
Y845971D01*
X1581679Y843638D01*
X1580805Y841596D01*
X1579495Y839846D01*
X1577966Y838680D01*
X1576220Y838388D01*
G01X1590008D02*
Y855888D01*
G01Y847430D02*
X1591100Y848888D01*
X1592192Y849763D01*
X1593938Y850054D01*
X1595248Y849763D01*
X1596777Y848596D01*
X1597432Y846846D01*
Y838388D01*
G01X1604670D02*
Y850054D01*
G01Y846846D02*
X1605325Y848305D01*
X1606417Y849471D01*
X1607945Y850054D01*
X1609473Y849471D01*
X1610565Y848305D01*
X1611220Y846846D01*
Y838388D01*
G01Y846846D02*
X1611875Y848305D01*
X1612966Y849471D01*
X1614495Y850054D01*
X1616023Y849471D01*
X1617115Y848305D01*
X1617770Y846555D01*
Y838388D01*
G01X1629812Y832555D02*
X1631995Y835471D01*
X1633087Y838388D01*
Y850054D01*
X1631995Y852971D01*
X1629812Y855888D01*
G01X1532470Y769088D02*
Y786588D01*
X1529850Y783088D01*
G01Y769088D02*
X1535090D01*
G01X1549970Y786588D02*
X1548223Y786005D01*
X1546913Y784546D01*
X1546040Y782797D01*
X1545385Y780463D01*
X1545167Y777838D01*
X1545385Y775213D01*
X1546040Y772879D01*
X1546913Y771129D01*
X1548223Y769671D01*
X1549970Y769088D01*
X1551716Y769671D01*
X1553027Y771129D01*
X1553900Y772879D01*
X1554555Y775213D01*
X1554773Y777838D01*
X1554555Y780463D01*
X1553900Y782797D01*
X1553027Y784546D01*
X1551716Y786005D01*
X1549970Y786588D01*
G01X1567470D02*
X1565723Y786005D01*
X1564413Y784546D01*
X1563540Y782797D01*
X1562885Y780463D01*
X1562667Y777838D01*
X1562885Y775213D01*
X1563540Y772879D01*
X1564413Y771129D01*
X1565723Y769671D01*
X1567470Y769088D01*
X1569216Y769671D01*
X1570527Y771129D01*
X1571400Y772879D01*
X1572055Y775213D01*
X1572273Y777838D01*
X1572055Y780463D01*
X1571400Y782797D01*
X1570527Y784546D01*
X1569216Y786005D01*
X1567470Y786588D01*
G01X1584970Y768505D02*
X1584533Y768796D01*
Y769380D01*
X1584970Y769671D01*
X1585407Y769380D01*
Y768796D01*
X1584970Y768505D01*
G01X1602470Y786588D02*
X1600723Y786005D01*
X1599413Y784546D01*
X1598540Y782797D01*
X1597885Y780463D01*
X1597667Y777838D01*
X1597885Y775213D01*
X1598540Y772879D01*
X1599413Y771129D01*
X1600723Y769671D01*
X1602470Y769088D01*
X1604216Y769671D01*
X1605527Y771129D01*
X1606400Y772879D01*
X1607055Y775213D01*
X1607273Y777838D01*
X1607055Y780463D01*
X1606400Y782797D01*
X1605527Y784546D01*
X1604216Y786005D01*
X1602470Y786588D01*
G01X1541220Y803738D02*
X1542748Y804030D01*
X1544495Y804904D01*
X1545587Y806362D01*
X1546023Y808405D01*
X1545587Y810446D01*
X1544277Y812196D01*
X1542312Y813071D01*
X1540128D01*
X1538818Y813655D01*
X1537726Y815113D01*
X1537290Y817154D01*
X1537945Y819196D01*
X1539473Y820655D01*
X1541220Y821238D01*
X1542966Y820655D01*
X1544495Y819196D01*
X1545150Y817154D01*
X1544713Y815113D01*
X1543622Y813655D01*
X1542312Y813071D01*
X1540128D01*
X1538163Y812196D01*
X1536853Y810446D01*
X1536417Y808405D01*
X1536853Y806362D01*
X1537945Y804904D01*
X1539692Y804030D01*
X1541220Y803738D01*
G01X1553917Y806362D02*
X1555226Y804904D01*
X1556755Y804030D01*
X1558720Y803738D01*
X1560685Y804321D01*
X1562213Y805488D01*
X1563305Y807529D01*
X1563523Y809863D01*
X1563087Y812196D01*
X1561995Y813655D01*
X1560466Y814821D01*
X1558938Y815113D01*
X1557410Y814821D01*
X1555445Y813655D01*
X1556100Y821238D01*
X1561995D01*
G01X1576220Y803155D02*
X1575783Y803446D01*
Y804030D01*
X1576220Y804321D01*
X1576657Y804030D01*
Y803446D01*
X1576220Y803155D01*
G01X1593720Y821238D02*
X1591973Y820655D01*
X1590663Y819196D01*
X1589790Y817447D01*
X1589135Y815113D01*
X1588917Y812488D01*
X1589135Y809863D01*
X1589790Y807529D01*
X1590663Y805779D01*
X1591973Y804321D01*
X1593720Y803738D01*
X1595466Y804321D01*
X1596777Y805779D01*
X1597650Y807529D01*
X1598305Y809863D01*
X1598523Y812488D01*
X1598305Y815113D01*
X1597650Y817447D01*
X1596777Y819196D01*
X1595466Y820655D01*
X1593720Y821238D01*
G01X1700920Y855888D02*
X1703976Y838388D01*
X1707470Y855888D01*
X1710963Y838388D01*
X1714020Y855888D01*
G01X1722350D02*
X1727590D01*
G01X1724970D02*
Y838388D01*
G01X1722350D02*
X1727590D01*
G01X1737667D02*
Y855888D01*
X1742033D01*
X1743780Y855013D01*
X1745090Y853846D01*
X1746182Y852097D01*
X1747055Y850054D01*
X1747273Y847138D01*
X1747055Y844221D01*
X1746182Y842179D01*
X1745090Y840429D01*
X1743780Y839263D01*
X1742033Y838388D01*
X1737667D01*
G01X1759970Y855888D02*
Y838388D01*
G01X1754948Y855888D02*
X1764992D01*
G01X1772885Y838388D02*
Y855888D01*
G01X1782055D02*
Y838388D01*
G01Y847138D02*
X1772885D01*
G01X1793878Y832555D02*
X1791695Y835471D01*
X1790603Y838388D01*
Y850054D01*
X1791695Y852971D01*
X1793878Y855888D01*
G01X1805920Y838388D02*
Y850054D01*
G01Y846846D02*
X1806575Y848305D01*
X1807667Y849471D01*
X1809195Y850054D01*
X1810723Y849471D01*
X1811815Y848305D01*
X1812470Y846846D01*
Y838388D01*
G01Y846846D02*
X1813125Y848305D01*
X1814216Y849471D01*
X1815745Y850054D01*
X1817273Y849471D01*
X1818365Y848305D01*
X1819020Y846555D01*
Y838388D01*
G01X1829970Y850054D02*
Y838388D01*
G01Y854721D02*
X1829533Y855013D01*
Y855596D01*
X1829970Y855888D01*
X1830407Y855596D01*
Y855013D01*
X1829970Y854721D01*
G01X1847470Y838388D02*
Y855888D01*
G01X1861695Y840429D02*
X1862787Y839263D01*
X1864315Y838388D01*
X1865625D01*
X1866935Y838971D01*
X1867808Y839846D01*
X1868245Y841012D01*
X1868027Y842763D01*
X1867153Y843638D01*
X1863223Y845388D01*
X1862350Y847430D01*
X1862787Y848888D01*
X1863660Y849763D01*
X1864970Y850054D01*
X1866280Y849763D01*
X1867590Y848888D01*
G01X1883562Y832555D02*
X1885745Y835471D01*
X1886837Y838388D01*
Y850054D01*
X1885745Y852971D01*
X1883562Y855888D01*
G01X1727590Y769088D02*
Y786588D01*
X1719511Y774046D01*
X1730429D01*
G01X1742470Y768505D02*
X1742033Y768796D01*
Y769380D01*
X1742470Y769671D01*
X1742907Y769380D01*
Y768796D01*
X1742470Y768505D01*
G01X1759970Y769088D02*
Y786588D01*
X1757350Y783088D01*
G01Y769088D02*
X1762590D01*
G01X1772667Y772588D02*
X1773976Y770546D01*
X1775723Y769380D01*
X1777688Y769088D01*
X1779435Y769380D01*
X1781182Y770838D01*
X1782273Y772588D01*
X1782492Y774338D01*
X1782055Y776379D01*
X1780527Y777838D01*
X1778998Y778421D01*
X1777033D01*
G01X1778998D02*
X1780308Y779296D01*
X1781400Y780754D01*
X1781837Y782504D01*
X1781400Y784255D01*
X1780308Y785713D01*
X1778343Y786588D01*
X1776378Y786296D01*
X1774413Y785129D01*
G01X1791040Y768505D02*
X1798900Y786588D01*
G01X1808758Y771129D02*
X1810287Y769671D01*
X1812033Y769088D01*
X1813780Y769671D01*
X1815308Y771421D01*
X1816400Y774046D01*
X1816837Y776671D01*
Y779879D01*
X1816400Y782504D01*
X1815308Y784838D01*
X1813998Y786005D01*
X1812470Y786588D01*
X1810723Y786005D01*
X1809413Y784838D01*
X1808540Y783088D01*
X1808103Y780754D01*
X1808540Y778713D01*
X1809632Y776671D01*
X1810942Y775504D01*
X1812470Y775213D01*
X1814216Y775796D01*
X1815527Y777255D01*
X1816837Y779879D01*
G01X1829970Y768505D02*
X1829533Y768796D01*
Y769380D01*
X1829970Y769671D01*
X1830407Y769380D01*
Y768796D01*
X1829970Y768505D01*
G01X1842667Y772588D02*
X1843976Y770546D01*
X1845723Y769380D01*
X1847688Y769088D01*
X1849435Y769380D01*
X1851182Y770838D01*
X1852273Y772588D01*
X1852492Y774338D01*
X1852055Y776379D01*
X1850527Y777838D01*
X1848998Y778421D01*
X1847033D01*
G01X1848998D02*
X1850308Y779296D01*
X1851400Y780754D01*
X1851837Y782504D01*
X1851400Y784255D01*
X1850308Y785713D01*
X1848343Y786588D01*
X1846378Y786296D01*
X1844413Y785129D01*
G01X1864533Y769088D02*
X1864970Y772879D01*
X1865625Y776088D01*
X1866498Y779005D01*
X1867590Y782213D01*
X1869337Y786588D01*
X1860603D01*
G01X1720167Y806362D02*
X1721476Y804904D01*
X1723005Y804030D01*
X1724970Y803738D01*
X1726935Y804321D01*
X1728463Y805488D01*
X1729555Y807529D01*
X1729773Y809863D01*
X1729337Y812196D01*
X1728245Y813655D01*
X1726716Y814821D01*
X1725188Y815113D01*
X1723660Y814821D01*
X1721695Y813655D01*
X1722350Y821238D01*
X1728245D01*
G01X1742470Y803155D02*
X1742033Y803446D01*
Y804030D01*
X1742470Y804321D01*
X1742907Y804030D01*
Y803446D01*
X1742470Y803155D01*
G01X1755167Y807238D02*
X1756476Y805196D01*
X1758223Y804030D01*
X1760188Y803738D01*
X1761935Y804030D01*
X1763682Y805488D01*
X1764773Y807238D01*
X1764992Y808988D01*
X1764555Y811029D01*
X1763027Y812488D01*
X1761498Y813071D01*
X1759533D01*
G01X1761498D02*
X1762808Y813946D01*
X1763900Y815404D01*
X1764337Y817154D01*
X1763900Y818905D01*
X1762808Y820363D01*
X1760843Y821238D01*
X1758878Y820946D01*
X1756913Y819779D01*
G01X1777470Y803738D02*
X1778998Y804030D01*
X1780745Y804904D01*
X1781837Y806362D01*
X1782273Y808405D01*
X1781837Y810446D01*
X1780527Y812196D01*
X1778562Y813071D01*
X1776378D01*
X1775068Y813655D01*
X1773976Y815113D01*
X1773540Y817154D01*
X1774195Y819196D01*
X1775723Y820655D01*
X1777470Y821238D01*
X1779216Y820655D01*
X1780745Y819196D01*
X1781400Y817154D01*
X1780963Y815113D01*
X1779872Y813655D01*
X1778562Y813071D01*
X1776378D01*
X1774413Y812196D01*
X1773103Y810446D01*
X1772667Y808405D01*
X1773103Y806362D01*
X1774195Y804904D01*
X1775942Y804030D01*
X1777470Y803738D01*
G01X1791040Y803155D02*
X1798900Y821238D01*
G01X1808322Y811029D02*
X1809850Y813071D01*
X1811160Y814238D01*
X1812907Y814821D01*
X1814435Y814238D01*
X1815527Y813071D01*
X1816400Y811321D01*
X1816618Y809280D01*
X1816400Y807529D01*
X1815527Y805779D01*
X1814216Y804321D01*
X1812688Y803738D01*
X1810942Y804321D01*
X1809413Y806071D01*
X1808540Y808696D01*
X1808322Y811613D01*
X1808758Y815404D01*
X1809413Y817447D01*
X1810505Y819488D01*
X1812033Y820946D01*
X1813562Y821238D01*
X1815090Y820655D01*
X1816182Y819196D01*
G01X1829970Y803155D02*
X1829533Y803446D01*
Y804030D01*
X1829970Y804321D01*
X1830407Y804030D01*
Y803446D01*
X1829970Y803155D01*
G01X1843322Y811029D02*
X1844850Y813071D01*
X1846160Y814238D01*
X1847907Y814821D01*
X1849435Y814238D01*
X1850527Y813071D01*
X1851400Y811321D01*
X1851618Y809280D01*
X1851400Y807529D01*
X1850527Y805779D01*
X1849216Y804321D01*
X1847688Y803738D01*
X1845942Y804321D01*
X1844413Y806071D01*
X1843540Y808696D01*
X1843322Y811613D01*
X1843758Y815404D01*
X1844413Y817447D01*
X1845505Y819488D01*
X1847033Y820946D01*
X1848562Y821238D01*
X1850090Y820655D01*
X1851182Y819196D01*
G01X1860822Y818321D02*
X1862132Y820071D01*
X1863660Y820946D01*
X1865407Y821238D01*
X1867590Y820655D01*
X1869118Y819196D01*
X1869555Y817447D01*
X1869337Y815696D01*
X1868463Y814238D01*
X1864097Y811321D01*
X1862132Y809280D01*
X1860822Y806362D01*
X1860385Y803738D01*
X1869555D01*
G01X1973917Y769088D02*
Y786588D01*
X1978283D01*
X1980030Y785713D01*
X1981340Y784546D01*
X1982432Y782797D01*
X1983305Y780754D01*
X1983523Y777838D01*
X1983305Y774921D01*
X1982432Y772879D01*
X1981340Y771129D01*
X1980030Y769963D01*
X1978283Y769088D01*
X1973917D01*
G01X1991853D02*
Y786588D01*
X1997093D01*
X1998840Y785713D01*
X2000150Y783671D01*
X2000587Y781338D01*
X2000150Y779005D01*
X1999058Y777255D01*
X1997093Y776379D01*
X1991853D01*
G01X1973917Y803738D02*
Y821238D01*
X1978283D01*
X1980030Y820363D01*
X1981340Y819196D01*
X1982432Y817447D01*
X1983305Y815404D01*
X1983523Y812488D01*
X1983305Y809571D01*
X1982432Y807529D01*
X1981340Y805779D01*
X1980030Y804613D01*
X1978283Y803738D01*
X1973917D01*
G01X1991853D02*
Y821238D01*
X1997093D01*
X1998840Y820363D01*
X2000150Y818321D01*
X2000587Y815988D01*
X2000150Y813655D01*
X1999058Y811905D01*
X1997093Y811029D01*
X1991853D01*
G01X1961220Y855888D02*
Y838388D01*
G01X1956198Y855888D02*
X1966242D01*
G01X1978720Y838388D02*
Y846263D01*
X1974353Y855888D01*
G01X1983087D02*
X1978720Y846263D01*
G01X1991853Y838388D02*
Y855888D01*
X1997093D01*
X1998840Y855013D01*
X2000150Y852971D01*
X2000587Y850638D01*
X2000150Y848305D01*
X1999058Y846555D01*
X1997093Y845679D01*
X1991853D01*
G01X2018087Y838388D02*
X2009353D01*
Y855888D01*
X2018087D01*
G01X2014593Y847430D02*
X2009353D01*
G01X2061853Y838388D02*
Y855888D01*
X2067312D01*
X2069058Y855013D01*
X2070150Y853846D01*
X2070587Y851513D01*
X2070150Y849179D01*
X2068840Y847721D01*
X2067312Y846846D01*
X2061853D01*
G01X2067312D02*
X2070587Y838388D01*
G01X2080445Y846263D02*
X2087432D01*
X2086777Y848305D01*
X2085685Y849471D01*
X2084157Y850054D01*
X2082628Y849763D01*
X2081318Y848888D01*
X2080445Y846846D01*
X2080008Y845096D01*
Y843346D01*
X2080445Y841596D01*
X2081537Y839846D01*
X2082847Y838680D01*
X2084375Y838388D01*
X2085903Y838971D01*
X2087432Y840721D01*
G01X2099910Y838388D02*
Y853263D01*
X2100347Y854721D01*
X2101220Y855596D01*
X2102530Y855888D01*
X2103840Y855305D01*
X2104495Y853846D01*
G01X2101875Y848888D02*
X2097508D01*
G01X2118720Y837805D02*
X2118283Y838096D01*
Y838680D01*
X2118720Y838971D01*
X2119157Y838680D01*
Y838096D01*
X2118720Y837805D01*
G01X2149353Y838388D02*
Y855888D01*
X2154593D01*
X2156340Y855013D01*
X2157650Y852971D01*
X2158087Y850638D01*
X2157650Y848305D01*
X2156558Y846555D01*
X2154593Y845679D01*
X2149353D01*
G01X2171220Y838388D02*
Y855888D01*
G01X2192650Y838388D02*
Y850054D01*
G01Y848013D02*
X2191777Y849179D01*
X2190466Y849763D01*
X2188938Y850054D01*
X2187410Y849471D01*
X2186100Y848305D01*
X2185226Y846555D01*
X2184790Y844221D01*
X2185226Y841888D01*
X2186100Y840138D01*
X2187410Y838971D01*
X2188938Y838388D01*
X2190466Y838680D01*
X2191777Y839554D01*
X2192650Y840721D01*
G01X2202508Y838388D02*
Y850054D01*
G01Y847138D02*
X2203382Y848596D01*
X2204692Y849763D01*
X2206438Y850054D01*
X2207966Y849763D01*
X2209277Y848596D01*
X2209932Y846555D01*
Y838388D01*
G01X2220445Y846263D02*
X2227432D01*
X2226777Y848305D01*
X2225685Y849471D01*
X2224157Y850054D01*
X2222628Y849763D01*
X2221318Y848888D01*
X2220445Y846846D01*
X2220008Y845096D01*
Y843346D01*
X2220445Y841596D01*
X2221537Y839846D01*
X2222847Y838680D01*
X2224375Y838388D01*
X2225903Y838971D01*
X2227432Y840721D01*
G01X2131853Y786588D02*
Y769088D01*
X2140587D01*
G01X2149572Y783671D02*
X2150882Y785421D01*
X2152410Y786296D01*
X2154157Y786588D01*
X2156340Y786005D01*
X2157868Y784546D01*
X2158305Y782797D01*
X2158087Y781046D01*
X2157213Y779588D01*
X2152847Y776671D01*
X2150882Y774630D01*
X2149572Y771712D01*
X2149135Y769088D01*
X2158305D01*
G01X2131853Y821238D02*
Y803738D01*
X2140587D01*
G01X2149572Y818321D02*
X2150882Y820071D01*
X2152410Y820946D01*
X2154157Y821238D01*
X2156340Y820655D01*
X2157868Y819196D01*
X2158305Y817447D01*
X2158087Y815696D01*
X2157213Y814238D01*
X2152847Y811321D01*
X2150882Y809280D01*
X2149572Y806362D01*
X2149135Y803738D01*
X2158305D01*
G01X2341520Y815404D02*
Y803738D01*
G01Y820071D02*
X2341083Y820363D01*
Y820946D01*
X2341520Y821238D01*
X2341957Y820946D01*
Y820363D01*
X2341520Y820071D01*
G01X2355745Y805779D02*
X2356837Y804613D01*
X2358365Y803738D01*
X2359675D01*
X2360985Y804321D01*
X2361858Y805196D01*
X2362295Y806362D01*
X2362077Y808113D01*
X2361203Y808988D01*
X2357273Y810738D01*
X2356400Y812780D01*
X2356837Y814238D01*
X2357710Y815113D01*
X2359020Y815404D01*
X2360330Y815113D01*
X2361640Y814238D01*
G01X2388998Y803738D02*
Y821238D01*
X2399042Y803738D01*
Y821238D01*
G01X2411520Y803738D02*
X2409773Y804030D01*
X2408245Y805196D01*
X2406935Y806946D01*
X2406061Y808988D01*
X2405625Y811321D01*
Y813655D01*
X2406061Y815988D01*
X2406935Y818030D01*
X2408245Y819779D01*
X2409773Y820946D01*
X2411520Y821238D01*
X2413266Y820946D01*
X2414795Y819779D01*
X2416105Y818030D01*
X2416979Y815988D01*
X2417415Y813655D01*
Y811321D01*
X2416979Y808988D01*
X2416105Y806946D01*
X2414795Y805196D01*
X2413266Y804030D01*
X2411520Y803738D01*
G01X2429020Y821238D02*
Y803738D01*
G01X2423998Y821238D02*
X2434042D01*
G01X2460308Y815404D02*
Y807238D01*
X2461182Y805196D01*
X2462492Y804030D01*
X2464020Y803738D01*
X2465548Y804030D01*
X2466858Y805196D01*
X2467732Y807238D01*
G01Y803738D02*
Y815404D01*
G01X2478245Y805779D02*
X2479337Y804613D01*
X2480865Y803738D01*
X2482175D01*
X2483485Y804321D01*
X2484358Y805196D01*
X2484795Y806362D01*
X2484577Y808113D01*
X2483703Y808988D01*
X2479773Y810738D01*
X2478900Y812780D01*
X2479337Y814238D01*
X2480210Y815113D01*
X2481520Y815404D01*
X2482830Y815113D01*
X2484140Y814238D01*
G01X2495745Y811613D02*
X2502732D01*
X2502077Y813655D01*
X2500985Y814821D01*
X2499457Y815404D01*
X2497928Y815113D01*
X2496618Y814238D01*
X2495745Y812196D01*
X2495308Y810446D01*
Y808696D01*
X2495745Y806946D01*
X2496837Y805196D01*
X2498147Y804030D01*
X2499675Y803738D01*
X2501203Y804321D01*
X2502732Y806071D01*
G01X2520450Y821238D02*
Y803738D01*
G01Y806362D02*
X2519577Y804904D01*
X2518266Y804030D01*
X2516738Y803738D01*
X2514992Y804321D01*
X2513682Y805779D01*
X2512808Y807529D01*
X2512590Y809571D01*
X2512808Y811613D01*
X2513682Y813363D01*
X2514992Y814821D01*
X2516738Y815404D01*
X2518266Y815113D01*
X2519358Y814529D01*
X2520450Y813363D01*
G01X2266717Y837805D02*
X2276323Y850638D01*
G01X2271520Y852971D02*
Y835471D01*
G01X2276323Y837805D02*
X2266717Y850638D01*
G01X2264970Y844221D02*
X2278070D01*
G01X2303682D02*
X2309358D01*
G01X2336717Y838388D02*
Y855888D01*
X2341083D01*
X2342830Y855013D01*
X2344140Y853846D01*
X2345232Y852097D01*
X2346105Y850054D01*
X2346323Y847138D01*
X2346105Y844221D01*
X2345232Y842179D01*
X2344140Y840429D01*
X2342830Y839263D01*
X2341083Y838388D01*
X2336717D01*
G01X2355745Y846263D02*
X2362732D01*
X2362077Y848305D01*
X2360985Y849471D01*
X2359457Y850054D01*
X2357928Y849763D01*
X2356618Y848888D01*
X2355745Y846846D01*
X2355308Y845096D01*
Y843346D01*
X2355745Y841596D01*
X2356837Y839846D01*
X2358147Y838680D01*
X2359675Y838388D01*
X2361203Y838971D01*
X2362732Y840721D01*
G01X2372808Y838388D02*
Y850054D01*
G01Y847138D02*
X2373682Y848596D01*
X2374992Y849763D01*
X2376738Y850054D01*
X2378266Y849763D01*
X2379577Y848596D01*
X2380232Y846555D01*
Y838388D01*
G01X2394020D02*
X2392710Y838680D01*
X2391400Y839846D01*
X2390526Y841888D01*
X2390090Y844221D01*
X2390526Y846555D01*
X2391400Y848596D01*
X2392710Y849763D01*
X2394020Y850054D01*
X2395330Y849763D01*
X2396640Y848596D01*
X2397513Y846555D01*
X2397732Y844221D01*
X2397513Y841888D01*
X2396640Y839846D01*
X2395330Y838680D01*
X2394020Y838388D01*
G01X2411520Y855888D02*
Y838388D01*
G01X2408463Y850054D02*
X2414577D01*
G01X2425745Y846263D02*
X2432732D01*
X2432077Y848305D01*
X2430985Y849471D01*
X2429457Y850054D01*
X2427928Y849763D01*
X2426618Y848888D01*
X2425745Y846846D01*
X2425308Y845096D01*
Y843346D01*
X2425745Y841596D01*
X2426837Y839846D01*
X2428147Y838680D01*
X2429675Y838388D01*
X2431203Y838971D01*
X2432732Y840721D01*
G01X2443245Y840429D02*
X2444337Y839263D01*
X2445865Y838388D01*
X2447175D01*
X2448485Y838971D01*
X2449358Y839846D01*
X2449795Y841012D01*
X2449577Y842763D01*
X2448703Y843638D01*
X2444773Y845388D01*
X2443900Y847430D01*
X2444337Y848888D01*
X2445210Y849763D01*
X2446520Y850054D01*
X2447830Y849763D01*
X2449140Y848888D01*
G01X2481520Y855888D02*
Y838388D01*
G01X2478463Y850054D02*
X2484577D01*
G01X2495308Y838388D02*
Y855888D01*
G01Y847430D02*
X2496400Y848888D01*
X2497492Y849763D01*
X2499238Y850054D01*
X2500548Y849763D01*
X2502077Y848596D01*
X2502732Y846846D01*
Y838388D01*
G01X2520450D02*
Y850054D01*
G01Y848013D02*
X2519577Y849179D01*
X2518266Y849763D01*
X2516738Y850054D01*
X2515210Y849471D01*
X2513900Y848305D01*
X2513026Y846555D01*
X2512590Y844221D01*
X2513026Y841888D01*
X2513900Y840138D01*
X2515210Y838971D01*
X2516738Y838388D01*
X2518266Y838680D01*
X2519577Y839554D01*
X2520450Y840721D01*
G01X2534020Y855888D02*
Y838388D01*
G01X2530963Y850054D02*
X2537077D01*
G01X2569020Y855888D02*
Y838388D01*
G01X2565963Y850054D02*
X2572077D01*
G01X2582808Y838388D02*
Y855888D01*
G01Y847430D02*
X2583900Y848888D01*
X2584992Y849763D01*
X2586738Y850054D01*
X2588048Y849763D01*
X2589577Y848596D01*
X2590232Y846846D01*
Y838388D01*
G01X2604020Y850054D02*
Y838388D01*
G01Y854721D02*
X2603583Y855013D01*
Y855596D01*
X2604020Y855888D01*
X2604457Y855596D01*
Y855013D01*
X2604020Y854721D01*
G01X2618245Y840429D02*
X2619337Y839263D01*
X2620865Y838388D01*
X2622175D01*
X2623485Y838971D01*
X2624358Y839846D01*
X2624795Y841012D01*
X2624577Y842763D01*
X2623703Y843638D01*
X2619773Y845388D01*
X2618900Y847430D01*
X2619337Y848888D01*
X2620210Y849763D01*
X2621520Y850054D01*
X2622830Y849763D01*
X2624140Y848888D01*
G01X2653900Y855888D02*
X2659140D01*
G01X2656520D02*
Y838388D01*
G01X2653900D02*
X2659140D01*
G01X2667470D02*
Y850054D01*
G01Y846846D02*
X2668125Y848305D01*
X2669217Y849471D01*
X2670745Y850054D01*
X2672273Y849471D01*
X2673365Y848305D01*
X2674020Y846846D01*
Y838388D01*
G01Y846846D02*
X2674675Y848305D01*
X2675766Y849471D01*
X2677295Y850054D01*
X2678823Y849471D01*
X2679915Y848305D01*
X2680570Y846555D01*
Y838388D01*
G01X2687590Y832555D02*
Y850054D01*
G01Y847430D02*
X2688682Y848888D01*
X2689773Y849763D01*
X2691520Y850054D01*
X2693048Y849763D01*
X2694577Y848305D01*
X2695232Y846263D01*
X2695450Y844221D01*
X2695232Y842179D01*
X2694577Y840138D01*
X2693266Y838971D01*
X2691520Y838388D01*
X2689992Y838680D01*
X2688463Y839554D01*
X2687590Y840721D01*
G01X2705745Y846263D02*
X2712732D01*
X2712077Y848305D01*
X2710985Y849471D01*
X2709457Y850054D01*
X2707928Y849763D01*
X2706618Y848888D01*
X2705745Y846846D01*
X2705308Y845096D01*
Y843346D01*
X2705745Y841596D01*
X2706837Y839846D01*
X2708147Y838680D01*
X2709675Y838388D01*
X2711203Y838971D01*
X2712732Y840721D01*
G01X2730450Y855888D02*
Y838388D01*
G01Y841012D02*
X2729577Y839554D01*
X2728266Y838680D01*
X2726738Y838388D01*
X2724992Y838971D01*
X2723682Y840429D01*
X2722808Y842179D01*
X2722590Y844221D01*
X2722808Y846263D01*
X2723682Y848013D01*
X2724992Y849471D01*
X2726738Y850054D01*
X2728266Y849763D01*
X2729358Y849179D01*
X2730450Y848013D01*
G01X2747950Y838388D02*
Y850054D01*
G01Y848013D02*
X2747077Y849179D01*
X2745766Y849763D01*
X2744238Y850054D01*
X2742710Y849471D01*
X2741400Y848305D01*
X2740526Y846555D01*
X2740090Y844221D01*
X2740526Y841888D01*
X2741400Y840138D01*
X2742710Y838971D01*
X2744238Y838388D01*
X2745766Y838680D01*
X2747077Y839554D01*
X2747950Y840721D01*
G01X2757808Y838388D02*
Y850054D01*
G01Y847138D02*
X2758682Y848596D01*
X2759992Y849763D01*
X2761738Y850054D01*
X2763266Y849763D01*
X2764577Y848596D01*
X2765232Y846555D01*
Y838388D01*
G01X2782513Y848596D02*
X2780985Y849763D01*
X2779675Y850054D01*
X2777928Y849471D01*
X2776618Y848305D01*
X2775745Y846263D01*
X2775526Y844221D01*
X2775745Y842179D01*
X2776618Y840429D01*
X2777928Y838971D01*
X2779675Y838388D01*
X2781203Y838971D01*
X2782513Y840138D01*
G01X2793245Y846263D02*
X2800232D01*
X2799577Y848305D01*
X2798485Y849471D01*
X2796957Y850054D01*
X2795428Y849763D01*
X2794118Y848888D01*
X2793245Y846846D01*
X2792808Y845096D01*
Y843346D01*
X2793245Y841596D01*
X2794337Y839846D01*
X2795647Y838680D01*
X2797175Y838388D01*
X2798703Y838971D01*
X2800232Y840721D01*
G01X1425733Y-51181D02*
X-29385D01*
G01X-33322Y-47244D02*
G03X-29385Y-51181I3937J0D01*
G01X-33322Y-47244D02*
Y893701D01*
G01X-7874Y102402D02*
Y212205D01*
G01Y102402D02*
G03X0Y94528I7874J0D01*
G01Y212205D02*
G03X-7874I-3937J0D01*
G01Y237402D02*
G03X0I3937J-1D01*
G01X-7874D02*
Y406693D01*
G01X0D02*
G03X-7874I-3937J0D01*
G01Y431890D02*
G03X0I3937J0D01*
G01X-7874D02*
Y601181D01*
G01X0D02*
G03X-7874I-3937J0D01*
G01Y626378D02*
Y795669D01*
G01Y626378D02*
G03X0I3937J0D01*
G01Y795669D02*
G03X-7874I-3937J0D01*
G01Y820866D02*
G03X0I3937J0D01*
G01X-7874Y844488D02*
Y820866D01*
G01X-3937Y848425D02*
G03X-7874Y844488I0J-3937D01*
G01X93307Y848425D02*
X-3937D01*
G01X-29385Y897638D02*
G03X-33322Y893701I0J-3937D01*
G01X-29385Y897638D02*
X93307D01*
G01X98425Y94528D02*
X0D01*
G01X1400000Y36220D02*
G03X1398031Y38189I-1969J0D01*
G01X1396654D01*
G02X1394685Y40157I0J1969D01*
G01Y71654D01*
G02X1396654Y73622I1969J-1D01*
G01X1398031D01*
G03X1400000Y75591I0J1969D01*
G01Y836614D01*
G03X1396063Y840551I-3937J0D01*
G01X1368504D01*
G02X1363386Y845669I0J5118D01*
G01Y871654D01*
G03X1361417Y873622I-1969J-1D01*
G01X1358268D01*
G02X1356299Y875591I0J1969D01*
G01Y892521D01*
X1352363Y897638D01*
X1218110D01*
X1214173Y892520D01*
Y875984D01*
G02X1205512I-4331J0D01*
G01Y892520D01*
X1201575Y897638D01*
X1029528D01*
X1025591Y892520D01*
Y875591D01*
G02X1023622Y873622I-1969J0D01*
G01X1020472D01*
G03X1018504Y871654I0J-1968D01*
G01Y845669D01*
G02X1013386Y840551I-5118J0D01*
G01X1008433D01*
G03X988748Y820866I0J-19685D01*
G01Y650669D01*
G02X983748Y645669I-5000J0D01*
G01X926819D01*
G02X921819Y650669I0J5000D01*
G01Y820866D01*
G03X902134Y840551I-19685J0D01*
G01X872441D01*
G02X867323Y845669I0J5118D01*
G01Y871654D01*
G03X865354Y873622I-1969J-1D01*
G01X862205D01*
G02X860236Y875591I0J1969D01*
G01Y892521D01*
X856300Y897638D01*
X722048D01*
X718110Y892519D01*
Y875984D01*
G02X709449I-4331J0D01*
G01Y892520D01*
X705512Y897638D01*
X533465D01*
X529528Y892520D01*
Y875591D01*
G02X527559Y873622I-1969J0D01*
G01X524409D01*
G03X522441Y871654I0J-1968D01*
G01Y845669D01*
G02X517323Y840551I-5118J0D01*
G01X455118D01*
G02X450000Y845669I0J5118D01*
G01Y871654D01*
G03X448031Y873622I-1968J0D01*
G01X444882D01*
G02X442913Y875591I0J1969D01*
G01Y892521D01*
X438977Y897638D01*
X304725D01*
X300787Y892519D01*
Y875984D01*
G02X292126I-4331J0D01*
G01Y892521D01*
X288190Y897638D01*
X116142D01*
X112205Y892520D01*
Y875591D01*
G02X110236Y873622I-1969J0D01*
G01X107087D01*
G03X105118Y871654I0J-1969D01*
G01Y845669D01*
G02X100000Y840551I-5118J0D01*
G01X3937D01*
G03X0Y836614I0J-3937D01*
G01Y110276D01*
G03X7874Y102402I7874J0D01*
G01X196654D01*
G02X204528Y94528I0J-7874D01*
G01Y7874D01*
G03X212402Y0I7874J0D01*
G01X471014D01*
G02X478888Y-7874I0J-7874D01*
G01Y-11811D01*
G03X486762Y-19685I7874J0D01*
G01X1302165D01*
G03X1306102Y-15748I0J3937D01*
G01Y-3937D01*
G02X1310039Y0I3937J0D01*
G01X1396063D01*
G03X1400000Y3937I0J3937D01*
G01Y36220D01*
G01X93307Y848425D02*
G03X97244Y852362I0J3937D01*
G01Y893701D02*
Y852362D01*
G01Y893701D02*
G03X93307Y897638I-3937J0D01*
G01X192717Y94528D02*
X123622D01*
G01Y102402D02*
G03Y94528I0J-3937D01*
G01X98425D02*
G03Y102402I0J3937D01*
G01X196654Y0D02*
G03X204528Y-7874I7874J0D01*
G01X196654Y0D02*
Y29961D01*
G01X204528D02*
G03X196654I-3937J0D01*
G01Y55157D02*
Y90591D01*
G01Y55157D02*
G03X204528I3937J0D01*
G01X196654Y90591D02*
G03X192717Y94528I-3937J0D01*
G01X232077Y-7874D02*
G03Y0I0J3937D01*
G01Y-7874D02*
X204528D01*
G01X434439D02*
X257274D01*
G01Y0D02*
G03Y-7874I0J-3937D01*
G01X365945Y38188D02*
G03X367914Y40156I0J1969D01*
G01X354134D02*
G03X356103Y38188I1969J1D01*
G01D02*
X365945D01*
G01X354134Y71653D02*
Y40156D01*
G01X367914Y71653D02*
G03X365945Y73621I-1969J-1D01*
G01X356103D02*
G03X354134Y71653I0J-1969D01*
G01X365945Y73621D02*
X356103D01*
G01X367914Y40156D02*
Y71653D01*
G01X434439Y-7874D02*
G03Y0I0J3937D01*
G01X471014Y-15748D02*
G03X463140Y-7874I-7874J0D01*
G01D02*
X459636D01*
G01Y0D02*
G03Y-7874I0J-3937D01*
G01X707234Y-27559D02*
X478888D01*
G01X471014Y-19685D02*
G03X478888Y-27559I7874J0D01*
G01X471014Y-19685D02*
Y-15748D01*
G01X870226Y-27559D02*
X732431D01*
G01Y-19685D02*
G03Y-27559I0J-3937D01*
G01X707234D02*
G03Y-19685I0J3937D01*
G01X870226Y-27559D02*
G03Y-19685I1J3937D01*
G01X1072589Y-27559D02*
X895423D01*
G01Y-19685D02*
G03Y-27559I0J-3937D01*
G01X1072589D02*
G03Y-19685I0J3937D01*
G01X1097785D02*
G03Y-27559I1J-3937D01*
G01X1336086Y-8662D02*
X1318701D01*
G03X1314764Y-12599I0J-3937D01*
G01Y-23622D01*
G02X1310827Y-27559I-3937J0D01*
G01X1097785D01*
G01X1336086Y-8662D02*
G03Y-1I0J4330D01*
G01X1361283D02*
G03Y-8662I0J-4330D01*
G01X1407874Y13026D02*
Y-4725D01*
G02X1403937Y-8662I-3937J0D01*
G01X1361283D01*
G01X1403937Y848425D02*
X1375197D01*
G01X1371260Y852362D02*
G03X1375197Y848425I3937J0D01*
G01X1371260Y852362D02*
Y893701D01*
G01X1375197Y897638D02*
G03X1371260Y893701I0J-3937D01*
G01X1375197Y897638D02*
X1425733D01*
G01X1407874Y30709D02*
Y219685D01*
G01X1400000Y30709D02*
G03X1407874I3937J0D01*
G01Y13026D02*
G03X1400000I-3937J-1D01*
G01X1407874Y219685D02*
G03X1400000I-3937J0D01*
G01Y244882D02*
G03X1407874I3937J0D01*
G01Y414173D02*
Y244882D01*
G01Y608661D02*
Y439370D01*
G01X1400000D02*
G03X1407874I3937J0D01*
G01Y414173D02*
G03X1400000I-3937J0D01*
G01X1407874Y608661D02*
G03X1400000I-3937J0D01*
G01Y626378D02*
G03X1407874I3937J0D01*
G01Y795669D02*
Y626378D01*
G01Y795669D02*
G03X1400000I-3937J0D01*
G01Y820866D02*
G03X1407874I3937J0D01*
G01Y844488D02*
Y820866D01*
G01Y844488D02*
G03X1403937Y848425I-3937J0D01*
G01X1429670Y893701D02*
Y-47244D01*
G01X1425733Y-51181D02*
G03X1429670Y-47244I0J3937D01*
G01Y893701D02*
G03X1425733Y897638I-3937J0D01*
G54D12*
G01X63650Y190060D02*
X75175Y201585D01*
G01X63650Y185450D02*
Y190060D01*
G01X68900Y180200D02*
X63650Y185450D01*
G01X68900Y180200D02*
X63650Y185450D01*
G01D02*
Y190060D01*
G01D02*
X75175Y201585D01*
G01X68900Y180200D02*
X63650Y185450D01*
G01D02*
Y190060D01*
G01D02*
X75175Y201585D01*
G01X63650Y190060D02*
X75175Y201585D01*
G01X63650Y185450D02*
Y190060D01*
G01X68900Y180200D02*
X63650Y185450D01*
G01X54266Y180056D02*
Y178598D01*
G01X52916Y178516D02*
Y180616D01*
G01X59900Y185690D02*
X54266Y180056D01*
G01X52916Y180616D02*
X58550Y186250D01*
G01X59900Y190600D02*
Y185690D01*
G01X58550Y186250D02*
Y190040D01*
G01X55675Y194825D02*
X59900Y190600D01*
G01X58550Y190040D02*
X54325Y194265D01*
G01X55675Y198525D02*
Y194825D01*
G01X54325Y194265D02*
Y198525D01*
G01X55600Y201750D02*
Y203050D01*
G01X54250Y201600D02*
Y203200D01*
G01X54266Y180056D02*
Y178598D01*
G01X52916Y178516D02*
Y180616D01*
G01X59900Y185690D02*
X54266Y180056D01*
G01X52916Y180616D02*
X58550Y186250D01*
G01X59900Y190600D02*
Y185690D01*
G01X58550Y186250D02*
Y190040D01*
G01X55675Y194825D02*
X59900Y190600D01*
G01X58550Y190040D02*
X54325Y194265D01*
G01X55675Y198525D02*
Y194825D01*
G01X54325Y194265D02*
Y198525D01*
G01X55600Y201750D02*
Y203050D01*
G01X54250Y201600D02*
Y203200D01*
G01X38950Y206450D02*
Y207950D01*
G01X40300Y206500D02*
Y207900D01*
G01X48880Y190772D02*
Y188380D01*
G01X50230Y191332D02*
Y188370D01*
G01X44902Y194750D02*
X48880Y190772D01*
G01X45462Y196100D02*
X50230Y191332D01*
G01X41340Y194750D02*
X44902D01*
G01X41900Y196100D02*
X45462D01*
G01X38975Y197115D02*
X41340Y194750D01*
G01X40325Y197675D02*
X41900Y196100D01*
G01X38975Y203325D02*
Y197115D01*
G01X40325Y203325D02*
Y197675D01*
G01X38950Y206450D02*
Y207950D01*
G01X40300Y206500D02*
Y207900D01*
G01X48880Y190772D02*
Y188380D01*
G01X50230Y191332D02*
Y188370D01*
G01X44902Y194750D02*
X48880Y190772D01*
G01X45462Y196100D02*
X50230Y191332D01*
G01X41340Y194750D02*
X44902D01*
G01X41900Y196100D02*
X45462D01*
G01X38975Y197115D02*
X41340Y194750D01*
G01X40325Y197675D02*
X41900Y196100D01*
G01X38975Y203325D02*
Y197115D01*
G01X40325Y203325D02*
Y197675D01*
G01X54325Y194265D02*
Y198525D01*
G01X55675D02*
Y194825D01*
G01X58550Y190040D02*
X54325Y194265D01*
G01X55675Y194825D02*
X59900Y190600D01*
G01X58550Y186250D02*
Y190040D01*
G01X59900Y190600D02*
Y185690D01*
G01X52916Y180616D02*
X58550Y186250D01*
G01X59900Y185690D02*
X54266Y180056D01*
G01X52916Y178516D02*
Y180616D01*
G01X54266Y180056D02*
Y178598D01*
G01X54250Y201600D02*
Y203200D01*
G01X55600Y201750D02*
Y203050D01*
G01X54325Y194265D02*
Y198525D01*
G01X55675D02*
Y194825D01*
G01X58550Y190040D02*
X54325Y194265D01*
G01X55675Y194825D02*
X59900Y190600D01*
G01X58550Y186250D02*
Y190040D01*
G01X59900Y190600D02*
Y185690D01*
G01X52916Y180616D02*
X58550Y186250D01*
G01X59900Y185690D02*
X54266Y180056D01*
G01X52916Y178516D02*
Y180616D01*
G01X54266Y180056D02*
Y178598D01*
G01X54250Y201600D02*
Y203200D01*
G01X55600Y201750D02*
Y203050D01*
G01X40300Y206500D02*
Y207900D01*
G01X38950Y206450D02*
Y207950D01*
G01X50230Y191332D02*
Y188370D01*
G01X48880Y190772D02*
Y188380D01*
G01X45462Y196100D02*
X50230Y191332D01*
G01X44902Y194750D02*
X48880Y190772D01*
G01X41900Y196100D02*
X45462D01*
G01X41340Y194750D02*
X44902D01*
G01X40325Y197675D02*
X41900Y196100D01*
G01X38975Y197115D02*
X41340Y194750D01*
G01X40325Y203325D02*
Y197675D01*
G01X38975Y203325D02*
Y197115D01*
G01X40300Y206500D02*
Y207900D01*
G01X38950Y206450D02*
Y207950D01*
G01X50230Y191332D02*
Y188370D01*
G01X48880Y190772D02*
Y188380D01*
G01X45462Y196100D02*
X50230Y191332D01*
G01X44902Y194750D02*
X48880Y190772D01*
G01X41900Y196100D02*
X45462D01*
G01X41340Y194750D02*
X44902D01*
G01X40325Y197675D02*
X41900Y196100D01*
G01X38975Y197115D02*
X41340Y194750D01*
G01X40325Y203325D02*
Y197675D01*
G01X38975Y203325D02*
Y197115D01*
G01X55675Y209275D02*
Y211003D01*
G01X54325Y209275D02*
Y211003D01*
G01X38975Y214075D02*
Y215803D01*
G01X40325Y214075D02*
Y215803D01*
G01Y214075D02*
Y215803D01*
G01X38975Y214075D02*
Y215803D01*
G01X54325Y209275D02*
Y211003D01*
G01X55675Y209275D02*
Y211003D01*
G01X38975Y214075D02*
Y215803D01*
G01X40325Y214075D02*
Y215803D01*
G01Y214075D02*
Y215803D01*
G01X38975Y214075D02*
Y215803D01*
G01X55675Y209275D02*
Y211003D01*
G01X54325Y209275D02*
Y211003D01*
G01Y209275D02*
Y211003D01*
G01X55675Y209275D02*
Y211003D01*
G01X53996Y268572D02*
X54879D01*
G01X54871Y267222D02*
X53436D01*
G01X53700Y268868D02*
X53996Y268572D01*
G01X53436Y267222D02*
X52350Y268308D01*
G01X53700Y271200D02*
Y268868D01*
G01X52350Y268308D02*
Y271760D01*
G01X58450Y275950D02*
X53700Y271200D01*
G01X52350Y271760D02*
X57100Y276510D01*
G01X58450Y277579D02*
Y275950D01*
G01X57100Y276510D02*
Y277544D01*
G01X62901Y272911D02*
Y277599D01*
G01X60800Y268900D02*
X64251Y272351D01*
G01X59450Y269460D02*
X62901Y272911D01*
G01X60800Y263510D02*
Y268900D01*
G01X59450Y262950D02*
Y269460D01*
G01X61307Y263003D02*
X60800Y263510D01*
G01X60747Y261653D02*
X59450Y262950D01*
G01X62778Y263003D02*
X61307D01*
G01X60747Y261653D02*
X59450Y262950D01*
G01X62772Y261653D02*
X60747D01*
G01X62901Y272911D02*
Y277599D01*
G01X60800Y268900D02*
X64251Y272351D01*
G01X59450Y269460D02*
X62901Y272911D01*
G01X60800Y263510D02*
Y268900D01*
G01X59450Y262950D02*
Y269460D01*
G01X61307Y263003D02*
X60800Y263510D01*
G01X60747Y261653D02*
X59450Y262950D01*
G01X62778Y263003D02*
X61307D01*
G01X60747Y261653D02*
X59450Y262950D01*
G01X62772Y261653D02*
X60747D01*
G01X57100Y276510D02*
Y277544D01*
G01X58450Y277579D02*
Y275950D01*
G01X52350Y271760D02*
X57100Y276510D01*
G01X58450Y275950D02*
X53700Y271200D01*
G01X52350Y268308D02*
Y271760D01*
G01X53700Y271200D02*
Y268868D01*
G01X53436Y267222D02*
X52350Y268308D01*
G01X53700Y268868D02*
X53996Y268572D01*
G01X54871Y267222D02*
X53436D01*
G01X53996Y268572D02*
X54879D01*
G01X62901Y272911D02*
Y277599D01*
G01X59450Y269460D02*
X62901Y272911D01*
G01X60800Y268900D02*
X64251Y272351D01*
G01X59450Y262950D02*
Y269460D01*
G01X60800Y263510D02*
Y268900D01*
G01X60747Y261653D02*
X59450Y262950D01*
G01X61307Y263003D02*
X60800Y263510D01*
G01X62778Y263003D02*
X61307D01*
G01X62772Y261653D02*
X60747D01*
G01X62778Y263003D02*
X61307D01*
G01X62901Y272911D02*
Y277599D01*
G01X59450Y269460D02*
X62901Y272911D01*
G01X60800Y268900D02*
X64251Y272351D01*
G01X59450Y262950D02*
Y269460D01*
G01X60800Y263510D02*
Y268900D01*
G01X60747Y261653D02*
X59450Y262950D01*
G01X61307Y263003D02*
X60800Y263510D01*
G01X62778Y263003D02*
X61307D01*
G01X62772Y261653D02*
X60747D01*
G01X62778Y263003D02*
X61307D01*
G01X53996Y268572D02*
X54879D01*
G01X54871Y267222D02*
X53436D01*
G01X53700Y268868D02*
X53996Y268572D01*
G01X53436Y267222D02*
X52350Y268308D01*
G01X53700Y271200D02*
Y268868D01*
G01X52350Y268308D02*
Y271760D01*
G01X58450Y275950D02*
X53700Y271200D01*
G01X52350Y271760D02*
X57100Y276510D01*
G01X58450Y277579D02*
Y275950D01*
G01X57100Y276510D02*
Y277544D01*
G01Y276510D02*
Y277544D01*
G01X58450Y277579D02*
Y275950D01*
G01X52350Y271760D02*
X57100Y276510D01*
G01X58450Y275950D02*
X53700Y271200D01*
G01X52350Y268308D02*
Y271760D01*
G01X53700Y271200D02*
Y268868D01*
G01X53436Y267222D02*
X52350Y268308D01*
G01X53700Y268868D02*
X53996Y268572D01*
G01X54871Y267222D02*
X53436D01*
G01X53996Y268572D02*
X54879D01*
G01X53996D02*
X54879D01*
G01X54871Y267222D02*
X53436D01*
G01X53700Y268868D02*
X53996Y268572D01*
G01X53436Y267222D02*
X52350Y268308D01*
G01X53700Y271200D02*
Y268868D01*
G01X52350Y268308D02*
Y271760D01*
G01X58450Y275950D02*
X53700Y271200D01*
G01X52350Y271760D02*
X57100Y276510D01*
G01X58450Y277579D02*
Y275950D01*
G01X57100Y276510D02*
Y277544D01*
G01X62901Y272911D02*
Y277599D01*
G01X60800Y268900D02*
X64251Y272351D01*
G01X59450Y269460D02*
X62901Y272911D01*
G01X60800Y263510D02*
Y268900D01*
G01X59450Y262950D02*
Y269460D01*
G01X61307Y263003D02*
X60800Y263510D01*
G01X60747Y261653D02*
X59450Y262950D01*
G01X62778Y263003D02*
X61307D01*
G01X60747Y261653D02*
X59450Y262950D01*
G01X62772Y261653D02*
X60747D01*
G01X57100Y276510D02*
Y277544D01*
G01X58450Y277579D02*
Y275950D01*
G01X52350Y271760D02*
X57100Y276510D01*
G01X58450Y275950D02*
X53700Y271200D01*
G01X52350Y268308D02*
Y271760D01*
G01X53700Y271200D02*
Y268868D01*
G01X53436Y267222D02*
X52350Y268308D01*
G01X53700Y268868D02*
X53996Y268572D01*
G01X54871Y267222D02*
X53436D01*
G01X53996Y268572D02*
X54879D01*
G01X62901Y272911D02*
Y277599D01*
G01X59450Y269460D02*
X62901Y272911D01*
G01X60800Y268900D02*
X64251Y272351D01*
G01X59450Y262950D02*
Y269460D01*
G01X60800Y263510D02*
Y268900D01*
G01X60747Y261653D02*
X59450Y262950D01*
G01X61307Y263003D02*
X60800Y263510D01*
G01X62778Y263003D02*
X61307D01*
G01X62772Y261653D02*
X60747D01*
G01X62778Y263003D02*
X61307D01*
G01X63124Y285953D02*
Y287332D01*
G01X64469Y284608D02*
X63124Y285953D01*
G01D02*
Y287332D01*
G01X64469Y284608D02*
X63124Y285953D01*
G01D02*
Y287332D01*
G01X64469Y284608D02*
X63124Y285953D01*
G01D02*
Y287332D01*
G01X64469Y284608D02*
X63124Y285953D01*
G01X91000Y209851D02*
Y208750D01*
G01X89650Y210001D02*
Y208600D01*
G01Y210001D02*
Y208600D01*
G01X91000Y209851D02*
Y208750D01*
G01X74286Y191332D02*
Y188598D01*
G01X72936Y188736D02*
Y191892D01*
G01X75454Y192500D02*
X74286Y191332D01*
G01X72936Y191892D02*
X74894Y193850D01*
G01X87535Y192500D02*
X75454D01*
G01X74894Y193850D02*
X86975D01*
G01X91075Y196040D02*
X87535Y192500D01*
G01X86975Y193850D02*
X89725Y196600D01*
G01X91075Y197825D02*
Y196040D01*
G01X89725Y196600D02*
Y197825D01*
G01X91150Y200900D02*
Y202600D01*
G01X89800Y201050D02*
Y202450D01*
G01X74286Y191332D02*
Y188598D01*
G01X72936Y188736D02*
Y191892D01*
G01X75454Y192500D02*
X74286Y191332D01*
G01X72936Y191892D02*
X74894Y193850D01*
G01X87535Y192500D02*
X75454D01*
G01X74894Y193850D02*
X86975D01*
G01X91075Y196040D02*
X87535Y192500D01*
G01X86975Y193850D02*
X89725Y196600D01*
G01X91075Y197825D02*
Y196040D01*
G01X89725Y196600D02*
Y197825D01*
G01X91150Y200900D02*
Y202600D01*
G01X89800Y201050D02*
Y202450D01*
G01X91000Y209851D02*
Y208750D01*
G01X89650Y210001D02*
Y208600D01*
G01X75174Y203225D02*
Y203226D01*
G01X76525Y203225D02*
Y201025D01*
G01X75175Y201585D02*
Y203224D01*
G01X76525Y203225D02*
Y201025D01*
G01D02*
X65000Y189500D01*
G01D02*
Y186010D01*
G01D02*
X70250Y180760D01*
G01X68900Y178500D02*
Y180200D01*
G01X70250Y180760D02*
Y178598D01*
G01X75125Y206325D02*
Y208025D01*
G01X76475Y206425D02*
Y208025D01*
G01X89725Y196600D02*
Y197825D01*
G01X91075D02*
Y196040D01*
G01X86975Y193850D02*
X89725Y196600D01*
G01X91075Y196040D02*
X87535Y192500D01*
G01X74894Y193850D02*
X86975D01*
G01X87535Y192500D02*
X75454D01*
G01X72936Y191892D02*
X74894Y193850D01*
G01X75454Y192500D02*
X74286Y191332D01*
G01X72936Y188736D02*
Y191892D01*
G01X74286Y191332D02*
Y188598D01*
G01X89800Y201050D02*
Y202450D01*
G01X91150Y200900D02*
Y202600D01*
G01X89725Y196600D02*
Y197825D01*
G01X91075D02*
Y196040D01*
G01X86975Y193850D02*
X89725Y196600D01*
G01X91075Y196040D02*
X87535Y192500D01*
G01X74894Y193850D02*
X86975D01*
G01X87535Y192500D02*
X75454D01*
G01X72936Y191892D02*
X74894Y193850D01*
G01X75454Y192500D02*
X74286Y191332D01*
G01X72936Y188736D02*
Y191892D01*
G01X74286Y191332D02*
Y188598D01*
G01X89800Y201050D02*
Y202450D01*
G01X91150Y200900D02*
Y202600D01*
G01X89650Y210001D02*
Y208600D01*
G01X91000Y209851D02*
Y208750D01*
G01X70250Y180760D02*
Y178598D01*
G01X68900Y178500D02*
Y180200D01*
G01X65000Y186010D02*
X70250Y180760D01*
G01X65000Y189500D02*
Y186010D01*
G01X76525Y201025D02*
X65000Y189500D01*
G01X76525Y203225D02*
Y201025D01*
G01X75174Y203225D02*
Y203226D01*
G01X75175Y201585D02*
Y203224D01*
G01X76475Y206425D02*
Y208025D01*
G01X75125Y206325D02*
Y208025D01*
G01X70250Y180760D02*
Y178598D01*
G01X68900Y178500D02*
Y180200D01*
G01X65000Y186010D02*
X70250Y180760D01*
G01X65000Y189500D02*
Y186010D01*
G01X76525Y201025D02*
X65000Y189500D01*
G01X76525Y203225D02*
Y201025D01*
G01X75174Y203225D02*
Y203226D01*
G01X75175Y201585D02*
Y203224D01*
G01X76475Y206425D02*
Y208025D01*
G01X75125Y206325D02*
Y208025D01*
G01X91000Y209851D02*
Y208750D01*
G01X89650Y210001D02*
Y208600D01*
G01Y210001D02*
Y208600D01*
G01X91000Y209851D02*
Y208750D01*
G01X75174Y203225D02*
Y203226D01*
G01X76525Y203225D02*
Y201025D01*
G01X75175Y201585D02*
Y203224D01*
G01X76525Y203225D02*
Y201025D01*
G01D02*
X65000Y189500D01*
G01D02*
Y186010D01*
G01D02*
X70250Y180760D01*
G01X68900Y178500D02*
Y180200D01*
G01X70250Y180760D02*
Y178598D01*
G01X75125Y206325D02*
Y208025D01*
G01X76475Y206425D02*
Y208025D01*
G01X89776Y221667D02*
Y220126D01*
G01X91126Y221651D02*
Y220024D01*
G01X76475Y225675D02*
Y227764D01*
G01X75125Y225675D02*
Y227764D01*
G01X91126Y221651D02*
Y220024D01*
G01X89776Y221667D02*
Y220126D01*
G01X75125Y225675D02*
Y227764D01*
G01X76475Y225675D02*
Y227764D01*
G01X91075Y211776D02*
Y213925D01*
G01X89725Y211776D02*
Y213925D01*
G01X75125Y214175D02*
Y215603D01*
G01X76475Y214175D02*
Y215603D01*
G01X75125Y217453D02*
Y219525D01*
G01X76475Y217453D02*
Y219525D01*
G01X75125Y214175D02*
Y215603D01*
G01X76475Y214175D02*
Y215603D01*
G01X75125Y217453D02*
Y219525D01*
G01X76475Y217453D02*
Y219525D01*
G01X89725Y211776D02*
Y213925D01*
G01X91075Y211776D02*
Y213925D01*
G01X76475Y214175D02*
Y215603D01*
G01X75125Y214175D02*
Y215603D01*
G01X76475Y217453D02*
Y219525D01*
G01X75125Y217453D02*
Y219525D01*
G01X76475Y214175D02*
Y215603D01*
G01X75125Y214175D02*
Y215603D01*
G01X76475Y217453D02*
Y219525D01*
G01X75125Y217453D02*
Y219525D01*
G01Y225675D02*
Y227764D01*
G01X76475Y225675D02*
Y227764D01*
G01Y225675D02*
Y227764D01*
G01X75125Y225675D02*
Y227764D01*
G01X91126Y221651D02*
Y220024D01*
G01X89776Y221667D02*
Y220126D01*
G01Y221667D02*
Y220126D01*
G01X91126Y221651D02*
Y220024D01*
G01X91075Y211776D02*
Y213925D01*
G01X89725Y211776D02*
Y213925D01*
G01Y211776D02*
Y213925D01*
G01X91075Y211776D02*
Y213925D01*
G01Y211776D02*
Y213925D01*
G01X89725Y211776D02*
Y213925D01*
G01X75125Y214175D02*
Y215603D01*
G01X76475Y214175D02*
Y215603D01*
G01X75125Y217453D02*
Y219525D01*
G01X76475Y217453D02*
Y219525D01*
G01X89725Y211776D02*
Y213925D01*
G01X91075Y211776D02*
Y213925D01*
G01X76475Y214175D02*
Y215603D01*
G01X75125Y214175D02*
Y215603D01*
G01X76475Y217453D02*
Y219525D01*
G01X75125Y217453D02*
Y219525D01*
G01X64251Y272351D02*
Y277551D01*
G01Y272351D02*
Y277551D01*
G01Y272351D02*
Y277551D01*
G01Y272351D02*
Y277551D01*
G01Y272351D02*
Y277551D01*
G01Y272351D02*
Y277551D01*
G01X64474Y286513D02*
Y287330D01*
G01X65029Y285958D02*
X64474Y286513D01*
G01X67035Y285958D02*
X65029D01*
G01X66475Y284608D02*
X64469D01*
G01X68238Y284755D02*
X67035Y285958D01*
G01X66888Y284195D02*
X66475Y284608D01*
G01X68238Y283444D02*
Y284755D01*
G01X66888Y283411D02*
Y284195D01*
G01X74142Y284691D02*
Y283348D01*
G01X72792Y285251D02*
Y283332D01*
G01X75412Y285961D02*
X74142Y284691D01*
G01X74062Y286521D02*
X72792Y285251D01*
G01X75412Y287318D02*
Y285961D01*
G01X74062Y287294D02*
Y286521D01*
G01X72792Y285251D02*
Y283332D01*
G01X74142Y284691D02*
Y283348D01*
G01X74062Y286521D02*
X72792Y285251D01*
G01X75412Y285961D02*
X74142Y284691D01*
G01X74062Y287294D02*
Y286521D01*
G01X75412Y287318D02*
Y285961D01*
G01X64474Y286513D02*
Y287330D01*
G01X65029Y285958D02*
X64474Y286513D01*
G01X66475Y284608D02*
X64469D01*
G01X67035Y285958D02*
X65029D01*
G01X66888Y284195D02*
X66475Y284608D01*
G01X68238Y284755D02*
X67035Y285958D01*
G01X66888Y283411D02*
Y284195D01*
G01X68238Y283444D02*
Y284755D01*
G01X74142Y284691D02*
Y283348D01*
G01X72792Y285251D02*
Y283332D01*
G01X75412Y285961D02*
X74142Y284691D01*
G01X74062Y286521D02*
X72792Y285251D01*
G01X75412Y287318D02*
Y285961D01*
G01X74062Y287294D02*
Y286521D01*
G01X72792Y285251D02*
Y283332D01*
G01X74142Y284691D02*
Y283348D01*
G01X74062Y286521D02*
X72792Y285251D01*
G01X75412Y285961D02*
X74142Y284691D01*
G01X74062Y287294D02*
Y286521D01*
G01X75412Y287318D02*
Y285961D01*
G01X64474Y286513D02*
Y287330D01*
G01X65029Y285958D02*
X64474Y286513D01*
G01X67035Y285958D02*
X65029D01*
G01X66475Y284608D02*
X64469D01*
G01X68238Y284755D02*
X67035Y285958D01*
G01X66888Y284195D02*
X66475Y284608D01*
G01X68238Y283444D02*
Y284755D01*
G01X66888Y283411D02*
Y284195D01*
G01X64474Y286513D02*
Y287330D01*
G01X65029Y285958D02*
X64474Y286513D01*
G01X66475Y284608D02*
X64469D01*
G01X67035Y285958D02*
X65029D01*
G01X66888Y284195D02*
X66475Y284608D01*
G01X68238Y284755D02*
X67035Y285958D01*
G01X66888Y283411D02*
Y284195D01*
G01X68238Y283444D02*
Y284755D01*
G54D13*
G01X75111Y320738D02*
Y321580D01*
G01X76311Y320240D02*
Y321360D01*
G01X72484Y318111D02*
X75111Y320738D01*
G01X74453Y318382D02*
X76311Y320240D01*
G01D02*
Y321360D01*
G01X75111Y320738D02*
Y321580D01*
G01X74453Y318382D02*
X76311Y320240D01*
G01X72484Y318111D02*
X75111Y320738D01*
G01X82400Y337802D02*
Y332850D01*
G01X83600Y338300D02*
Y332850D01*
G01X81277Y338925D02*
X82400Y337802D01*
G01X82477Y339423D02*
X83600Y338300D01*
G01X81277Y342500D02*
Y338925D01*
G01X82477Y342500D02*
Y339423D01*
G01X83600Y338300D02*
Y332850D01*
G01X82400Y337802D02*
Y332850D01*
G01X82477Y339423D02*
X83600Y338300D01*
G01X81277Y338925D02*
X82400Y337802D01*
G01X82477Y342500D02*
Y339423D01*
G01X81277Y342500D02*
Y338925D01*
G01X68980Y323648D02*
Y318342D01*
G01X70180Y323150D02*
Y318222D01*
G01X69800Y324468D02*
X68980Y323648D01*
G01X71000Y323970D02*
X70180Y323150D01*
G01X69800Y336050D02*
Y324468D01*
G01X71000Y336548D02*
Y323970D01*
G01X68150Y337700D02*
X69800Y336050D01*
G01X68648Y338900D02*
X71000Y336548D01*
G01X65826Y337700D02*
X68150D01*
G01X66324Y338900D02*
X68648D01*
G01X64100Y339426D02*
X65826Y337700D01*
G01X65300Y339924D02*
X66324Y338900D01*
G01X64100Y341000D02*
Y339426D01*
G01X65300Y341200D02*
Y339924D01*
G01X70180Y323150D02*
Y318222D01*
G01X68980Y323648D02*
Y318342D01*
G01X71000Y323970D02*
X70180Y323150D01*
G01X69800Y324468D02*
X68980Y323648D01*
G01X71000Y336548D02*
Y323970D01*
G01X69800Y336050D02*
Y324468D01*
G01X68648Y338900D02*
X71000Y336548D01*
G01X68150Y337700D02*
X69800Y336050D01*
G01X66324Y338900D02*
X68648D01*
G01X65826Y337700D02*
X68150D01*
G01X65300Y339924D02*
X66324Y338900D01*
G01X64100Y339426D02*
X65826Y337700D01*
G01X65300Y341200D02*
Y339924D01*
G01X64100Y341000D02*
Y339426D01*
G01X78740Y320118D02*
Y318733D01*
G01X79940Y319620D02*
Y318801D01*
G01X82370Y323748D02*
X78740Y320118D01*
G01X83570Y323250D02*
X79940Y319620D01*
G01X82370Y327180D02*
Y323748D01*
G01X83570Y327120D02*
Y323250D01*
G01X79940Y319620D02*
Y318801D01*
G01X78740Y320118D02*
Y318733D01*
G01X83570Y323250D02*
X79940Y319620D01*
G01X82370Y323748D02*
X78740Y320118D01*
G01X83570Y327120D02*
Y323250D01*
G01X82370Y327180D02*
Y323748D01*
G01X75111Y320738D02*
Y321580D01*
G01X76311Y320240D02*
Y321360D01*
G01X72484Y318111D02*
X75111Y320738D01*
G01X74453Y318382D02*
X76311Y320240D01*
G01D02*
Y321360D01*
G01X75111Y320738D02*
Y321580D01*
G01X74453Y318382D02*
X76311Y320240D01*
G01X72484Y318111D02*
X75111Y320738D01*
G01X82400Y337802D02*
Y332850D01*
G01X83600Y338300D02*
Y332850D01*
G01X81277Y338925D02*
X82400Y337802D01*
G01X82477Y339423D02*
X83600Y338300D01*
G01X81277Y342500D02*
Y338925D01*
G01X82477Y342500D02*
Y339423D01*
G01X83600Y338300D02*
Y332850D01*
G01X82400Y337802D02*
Y332850D01*
G01X82477Y339423D02*
X83600Y338300D01*
G01X81277Y338925D02*
X82400Y337802D01*
G01X82477Y342500D02*
Y339423D01*
G01X81277Y342500D02*
Y338925D01*
G01X70180Y323150D02*
Y318222D01*
G01X68980Y323648D02*
Y318342D01*
G01X71000Y323970D02*
X70180Y323150D01*
G01X69800Y324468D02*
X68980Y323648D01*
G01X71000Y336548D02*
Y323970D01*
G01X69800Y336050D02*
Y324468D01*
G01X68648Y338900D02*
X71000Y336548D01*
G01X68150Y337700D02*
X69800Y336050D01*
G01X66324Y338900D02*
X68648D01*
G01X65826Y337700D02*
X68150D01*
G01X65300Y339924D02*
X66324Y338900D01*
G01X64100Y339426D02*
X65826Y337700D01*
G01X65300Y341200D02*
Y339924D01*
G01X64100Y341000D02*
Y339426D01*
G01X68980Y323648D02*
Y318342D01*
G01X70180Y323150D02*
Y318222D01*
G01X69800Y324468D02*
X68980Y323648D01*
G01X71000Y323970D02*
X70180Y323150D01*
G01X69800Y336050D02*
Y324468D01*
G01X71000Y336548D02*
Y323970D01*
G01X68150Y337700D02*
X69800Y336050D01*
G01X68648Y338900D02*
X71000Y336548D01*
G01X65826Y337700D02*
X68150D01*
G01X66324Y338900D02*
X68648D01*
G01X64100Y339426D02*
X65826Y337700D01*
G01X65300Y339924D02*
X66324Y338900D01*
G01X64100Y341000D02*
Y339426D01*
G01X65300Y341200D02*
Y339924D01*
G01X82809Y444840D02*
X76233Y454964D01*
G01X87523Y441488D02*
X82952Y444692D01*
G01X83746Y445602D02*
X88210Y442473D01*
G01X87726Y441359D02*
G02X87523Y441488I1614J2763D01*
G01X88210Y442473D02*
G03X88337Y442392I1138J1644D01*
G01X88237Y441054D02*
X87726Y441359D01*
G01X88340Y442390D02*
X88851Y442086D01*
G01X89246Y440667D02*
G02X88237Y441054I625J3139D01*
G01X88851Y442086D02*
G03X89481Y441844I1022J1719D01*
G01X91749Y440167D02*
X89246Y440667D01*
G01X89481Y441844D02*
X91984Y441344D01*
G01X92917Y440151D02*
G02X91749Y440167I-541J3154D01*
G01X91984Y441344D02*
G03X92714Y441334I392J1961D01*
G01X93193Y440198D02*
X92917Y440151D01*
G01X92714Y441334D02*
X93100Y441400D01*
G01X93198Y440198D02*
X93193D01*
G01X92714Y441334D02*
X93100Y441400D01*
G01X92714Y441334D02*
X93100Y441400D01*
G01X93193Y440198D02*
X92917Y440151D01*
G01X93198Y440198D02*
X93193D01*
G01X91984Y441344D02*
G03X92714Y441334I392J1961D01*
G01X92917Y440151D02*
G02X91749Y440167I-541J3154D01*
G01X89481Y441844D02*
X91984Y441344D01*
G01X91749Y440167D02*
X89246Y440667D01*
G01X88851Y442086D02*
G03X89481Y441844I1022J1719D01*
G01X89246Y440667D02*
G02X88237Y441054I625J3139D01*
G01X88340Y442390D02*
X88851Y442086D01*
G01X88237Y441054D02*
X87726Y441359D01*
G01X88210Y442473D02*
G03X88337Y442392I1138J1644D01*
G01X87726Y441359D02*
G02X87523Y441488I1614J2763D01*
G01X83746Y445602D02*
X88210Y442473D01*
G01X87523Y441488D02*
X82952Y444692D01*
G01X82809Y444840D02*
X76233Y454964D01*
G01X91455Y429333D02*
X94683D01*
G01X91455Y428133D02*
X94688D01*
G01X90630Y429584D02*
G03X91455Y429333I825J1230D01*
G01X89961Y428587D02*
G03X91455Y428133I1493J2228D01*
G01X87414Y431743D02*
X90630Y429584D01*
G01X82965Y433283D02*
X89961Y428587D01*
G01X84974Y433381D02*
X85893Y433561D01*
G01X82965Y433283D02*
X89961Y428587D01*
G01X83634Y434280D02*
X84974Y433381D01*
G01X82965Y433283D02*
X89961Y428587D01*
G01X83196Y434717D02*
G03X83634Y434280I1336J901D01*
G01X82201Y434046D02*
G03X82965Y433283I2332J1571D01*
G01X82294Y436056D02*
X83196Y434717D01*
G01X70590Y451284D02*
X82201Y434046D01*
G01X79751Y439832D02*
X80653Y438493D01*
G01X70590Y451284D02*
X82201Y434046D01*
G01X77208Y443608D02*
X78110Y442269D01*
G01X70590Y451284D02*
X82201Y434046D01*
G01X70590Y451284D02*
X82201Y434046D01*
G01X70590Y451284D02*
X82201Y434046D01*
G01X97540Y429196D02*
X98592D01*
G01X97262Y427996D02*
X98850D01*
G01X91455Y428133D02*
X94688D01*
G01X91455Y429333D02*
X94683D01*
G01X89961Y428587D02*
G03X91455Y428133I1493J2228D01*
G01X90630Y429584D02*
G03X91455Y429333I825J1230D01*
G01X82965Y433283D02*
X89961Y428587D01*
G01X87414Y431743D02*
X90630Y429584D01*
G01X84974Y433381D02*
X85893Y433561D01*
G01X83634Y434280D02*
X84974Y433381D01*
G01X82201Y434046D02*
G03X82965Y433283I2332J1571D01*
G01X83196Y434717D02*
G03X83634Y434280I1336J901D01*
G01X70590Y451284D02*
X82201Y434046D01*
G01X82294Y436056D02*
X83196Y434717D01*
G01X79751Y439832D02*
X80653Y438493D01*
G01X77208Y443608D02*
X78110Y442269D01*
G01X97262Y427996D02*
X98850D01*
G01X97540Y429196D02*
X98592D01*
G01X91455Y429333D02*
X94683D01*
G01X91455Y428133D02*
X94688D01*
G01X90630Y429584D02*
G03X91455Y429333I825J1230D01*
G01X89961Y428587D02*
G03X91455Y428133I1493J2228D01*
G01X87414Y431743D02*
X90630Y429584D01*
G01X82965Y433283D02*
X89961Y428587D01*
G01X84974Y433381D02*
X85893Y433561D01*
G01X82965Y433283D02*
X89961Y428587D01*
G01X83634Y434280D02*
X84974Y433381D01*
G01X82965Y433283D02*
X89961Y428587D01*
G01X83196Y434717D02*
G03X83634Y434280I1336J901D01*
G01X82201Y434046D02*
G03X82965Y433283I2332J1571D01*
G01X82294Y436056D02*
X83196Y434717D01*
G01X70590Y451284D02*
X82201Y434046D01*
G01X79751Y439832D02*
X80653Y438493D01*
G01X70590Y451284D02*
X82201Y434046D01*
G01X77208Y443608D02*
X78110Y442269D01*
G01X70590Y451284D02*
X82201Y434046D01*
G01X70590Y451284D02*
X82201Y434046D01*
G01X70590Y451284D02*
X82201Y434046D01*
G01X97540Y429196D02*
X98592D01*
G01X97262Y427996D02*
X98850D01*
G01X91455Y429333D02*
X94683D01*
G01X91455Y428133D02*
X94688D01*
G01X90630Y429584D02*
G03X91455Y429333I825J1230D01*
G01X89961Y428587D02*
G03X91455Y428133I1493J2228D01*
G01X87414Y431743D02*
X90630Y429584D01*
G01X82965Y433283D02*
X89961Y428587D01*
G01X84974Y433381D02*
X85893Y433561D01*
G01X82965Y433283D02*
X89961Y428587D01*
G01X83634Y434280D02*
X84974Y433381D01*
G01X82965Y433283D02*
X89961Y428587D01*
G01X83196Y434717D02*
G03X83634Y434280I1336J901D01*
G01X82201Y434046D02*
G03X82965Y433283I2332J1571D01*
G01X82294Y436056D02*
X83196Y434717D01*
G01X70590Y451284D02*
X82201Y434046D01*
G01X79751Y439832D02*
X80653Y438493D01*
G01X70590Y451284D02*
X82201Y434046D01*
G01X77208Y443608D02*
X78110Y442269D01*
G01X70590Y451284D02*
X82201Y434046D01*
G01X70590Y451284D02*
X82201Y434046D01*
G01X70590Y451284D02*
X82201Y434046D01*
G01X97540Y429196D02*
X98592D01*
G01X97262Y427996D02*
X98850D01*
G01X91455Y428133D02*
X94688D01*
G01X91455Y429333D02*
X94683D01*
G01X89961Y428587D02*
G03X91455Y428133I1493J2228D01*
G01X90630Y429584D02*
G03X91455Y429333I825J1230D01*
G01X82965Y433283D02*
X89961Y428587D01*
G01X87414Y431743D02*
X90630Y429584D01*
G01X84974Y433381D02*
X85893Y433561D01*
G01X83634Y434280D02*
X84974Y433381D01*
G01X82201Y434046D02*
G03X82965Y433283I2332J1571D01*
G01X83196Y434717D02*
G03X83634Y434280I1336J901D01*
G01X70590Y451284D02*
X82201Y434046D01*
G01X82294Y436056D02*
X83196Y434717D01*
G01X79751Y439832D02*
X80653Y438493D01*
G01X77208Y443608D02*
X78110Y442269D01*
G01X97262Y427996D02*
X98850D01*
G01X97540Y429196D02*
X98592D01*
G01X91455Y428133D02*
X94688D01*
G01X91455Y429333D02*
X94683D01*
G01X89961Y428587D02*
G03X91455Y428133I1493J2228D01*
G01X90630Y429584D02*
G03X91455Y429333I825J1230D01*
G01X82965Y433283D02*
X89961Y428587D01*
G01X87414Y431743D02*
X90630Y429584D01*
G01X84974Y433381D02*
X85893Y433561D01*
G01X83634Y434280D02*
X84974Y433381D01*
G01X82201Y434046D02*
G03X82965Y433283I2332J1571D01*
G01X83196Y434717D02*
G03X83634Y434280I1336J901D01*
G01X70590Y451284D02*
X82201Y434046D01*
G01X82294Y436056D02*
X83196Y434717D01*
G01X79751Y439832D02*
X80653Y438493D01*
G01X77208Y443608D02*
X78110Y442269D01*
G01X97262Y427996D02*
X98850D01*
G01X97540Y429196D02*
X98592D01*
G01X82809Y444840D02*
X76233Y454964D01*
G01X87523Y441488D02*
X82952Y444692D01*
G01X83746Y445602D02*
X88210Y442473D01*
G01X87726Y441359D02*
G02X87523Y441488I1614J2763D01*
G01X88210Y442473D02*
G03X88337Y442392I1138J1644D01*
G01X88237Y441054D02*
X87726Y441359D01*
G01X88340Y442390D02*
X88851Y442086D01*
G01X89246Y440667D02*
G02X88237Y441054I625J3139D01*
G01X88851Y442086D02*
G03X89481Y441844I1022J1719D01*
G01X91749Y440167D02*
X89246Y440667D01*
G01X89481Y441844D02*
X91984Y441344D01*
G01X92917Y440151D02*
G02X91749Y440167I-541J3154D01*
G01X91984Y441344D02*
G03X92714Y441334I392J1961D01*
G01X93193Y440198D02*
X92917Y440151D01*
G01X92714Y441334D02*
X93100Y441400D01*
G01X93198Y440198D02*
X93193D01*
G01X92714Y441334D02*
X93100Y441400D01*
G01X92714Y441334D02*
X93100Y441400D01*
G01X93193Y440198D02*
X92917Y440151D01*
G01X93198Y440198D02*
X93193D01*
G01X91984Y441344D02*
G03X92714Y441334I392J1961D01*
G01X92917Y440151D02*
G02X91749Y440167I-541J3154D01*
G01X89481Y441844D02*
X91984Y441344D01*
G01X91749Y440167D02*
X89246Y440667D01*
G01X88851Y442086D02*
G03X89481Y441844I1022J1719D01*
G01X89246Y440667D02*
G02X88237Y441054I625J3139D01*
G01X88340Y442390D02*
X88851Y442086D01*
G01X88237Y441054D02*
X87726Y441359D01*
G01X88210Y442473D02*
G03X88337Y442392I1138J1644D01*
G01X87726Y441359D02*
G02X87523Y441488I1614J2763D01*
G01X83746Y445602D02*
X88210Y442473D01*
G01X87523Y441488D02*
X82952Y444692D01*
G01X82809Y444840D02*
X76233Y454964D01*
G01X75857Y478725D02*
G02X76759Y480379I3260J-705D01*
G01X77608Y479530D02*
G03X77031Y478471I1510J-1509D01*
G01X73446Y467554D02*
X75857Y478725D01*
G01X77031Y478471D02*
X74646Y467425D01*
G01X73446Y466671D02*
Y467554D01*
G01X74646Y467425D02*
Y466728D01*
G01X73593Y465114D02*
X73446Y466671D01*
G01X74646Y466728D02*
X74782Y465296D01*
G01X75241Y457361D02*
X73593Y465114D01*
G01X74782Y465296D02*
X76415Y457610D01*
G01X76233Y454964D02*
G02X75241Y457361I5967J3873D01*
G01X76415Y457610D02*
G03X77240Y455618I5785J1229D01*
G01D02*
X83746Y445602D01*
G01X77240Y455618D02*
X83746Y445602D01*
G01X76415Y457610D02*
G03X77240Y455618I5785J1229D01*
G01X76233Y454964D02*
G02X75241Y457361I5967J3873D01*
G01X74782Y465296D02*
X76415Y457610D01*
G01X75241Y457361D02*
X73593Y465114D01*
G01X74646Y466728D02*
X74782Y465296D01*
G01X73593Y465114D02*
X73446Y466671D01*
G01X74646Y467425D02*
Y466728D01*
G01X73446Y466671D02*
Y467554D01*
G01X77031Y478471D02*
X74646Y467425D01*
G01X73446Y467554D02*
X75857Y478725D01*
G01X77608Y479530D02*
G03X77031Y478471I1510J-1509D01*
G01X75857Y478725D02*
G02X76759Y480379I3260J-705D01*
G01X74665Y447383D02*
X75567Y446044D01*
G01X71716Y451762D02*
X73024Y449820D01*
G01X71380Y453341D02*
X71716Y451762D01*
G01X67388Y466348D02*
X70590Y451286D01*
G01X70434Y457794D02*
X70770Y456215D01*
G01X67388Y466348D02*
X70590Y451286D01*
G01X68613Y466359D02*
X69823Y460667D01*
G01X67388Y466348D02*
X70590Y451286D01*
G01X68921Y467943D02*
X68613Y466359D01*
G01X70095Y480268D02*
X67388Y466348D01*
G01X69790Y472411D02*
X69482Y470827D01*
G01X70095Y480268D02*
X67388Y466348D01*
G01X71227Y479799D02*
X70351Y475295D01*
G01X70095Y480268D02*
X67388Y466348D01*
G01X74665Y447383D02*
X75567Y446044D01*
G01X71716Y451762D02*
X73024Y449820D01*
G01X67388Y466348D02*
X70590Y451286D01*
G01X71380Y453341D02*
X71716Y451762D01*
G01X70434Y457794D02*
X70770Y456215D01*
G01X68613Y466359D02*
X69823Y460667D01*
G01X70095Y480268D02*
X67388Y466348D01*
G01X68921Y467943D02*
X68613Y466359D01*
G01X69790Y472411D02*
X69482Y470827D01*
G01X71227Y479799D02*
X70351Y475295D01*
G01X88099Y451645D02*
X88903D01*
G01X88100Y450445D02*
X88600D01*
G01X86586Y452018D02*
G03X88099Y451645I1535J2973D01*
G01X86029Y450954D02*
G03X88100Y450445I2070J3955D01*
G01X86078Y452347D02*
G03X86586Y452018I2021J2563D01*
G01X86029Y450954D02*
G03X88100Y450445I2070J3955D01*
G01X85334Y451404D02*
G03X86029Y450954I2764J3506D01*
G01X86030Y452389D02*
G03X86078Y452347I375J380D01*
G01X85181Y451540D02*
G03X85334Y451404I1227J1226D01*
G01X85622Y452797D02*
X86030Y452389D01*
G01X84684Y452037D02*
X85181Y451540D01*
G01X81847Y458610D02*
X85622Y452797D01*
G01X80840Y457956D02*
X84684Y452037D01*
G01X81180Y460220D02*
G03X81847Y458610I4676J994D01*
G01X80006Y459971D02*
G03X80840Y457956I5851J1241D01*
G01X79934Y466087D02*
X81180Y460220D01*
G01X78760Y465838D02*
X80006Y459971D01*
G01X79934Y467797D02*
G03Y466087I4025J-855D01*
G01X78760Y468046D02*
G03Y465838I5199J-1104D01*
G01X80741Y471597D02*
X79934Y467797D01*
G01X79567Y471846D02*
X78760Y468046D01*
G01X81486Y473395D02*
G03X80741Y471597I4478J-2909D01*
G01X80479Y474049D02*
G03X79567Y471846I5485J-3561D01*
G01X83324Y476225D02*
X81486Y473395D01*
G01X82317Y476879D02*
X80479Y474049D01*
G01X85005Y477906D02*
G03X83324Y476225I3115J-4796D01*
G01X84351Y478913D02*
G03X82317Y476879I3769J-5803D01*
G01X89235Y480654D02*
X85005Y477906D01*
G01X88581Y481661D02*
X84351Y478913D01*
G01X88100Y450445D02*
X88600D01*
G01X88099Y451645D02*
X88903D01*
G01X86029Y450954D02*
G03X88100Y450445I2070J3955D01*
G01X86586Y452018D02*
G03X88099Y451645I1535J2973D01*
G01X86078Y452347D02*
G03X86586Y452018I2021J2563D01*
G01X85334Y451404D02*
G03X86029Y450954I2764J3506D01*
G01X86078Y452347D02*
G03X86586Y452018I2021J2563D01*
G01X85181Y451540D02*
G03X85334Y451404I1227J1226D01*
G01X86030Y452389D02*
G03X86078Y452347I375J380D01*
G01X84684Y452037D02*
X85181Y451540D01*
G01X85622Y452797D02*
X86030Y452389D01*
G01X80840Y457956D02*
X84684Y452037D01*
G01X81847Y458610D02*
X85622Y452797D01*
G01X80006Y459971D02*
G03X80840Y457956I5851J1241D01*
G01X81180Y460220D02*
G03X81847Y458610I4676J994D01*
G01X78760Y465838D02*
X80006Y459971D01*
G01X79934Y466087D02*
X81180Y460220D01*
G01X78760Y468046D02*
G03Y465838I5199J-1104D01*
G01X79934Y467797D02*
G03Y466087I4025J-855D01*
G01X79567Y471846D02*
X78760Y468046D01*
G01X80741Y471597D02*
X79934Y467797D01*
G01X80479Y474049D02*
G03X79567Y471846I5485J-3561D01*
G01X81486Y473395D02*
G03X80741Y471597I4478J-2909D01*
G01X82317Y476879D02*
X80479Y474049D01*
G01X83324Y476225D02*
X81486Y473395D01*
G01X84351Y478913D02*
G03X82317Y476879I3769J-5803D01*
G01X85005Y477906D02*
G03X83324Y476225I3115J-4796D01*
G01X88581Y481661D02*
X84351Y478913D01*
G01X89235Y480654D02*
X85005Y477906D01*
G01X74665Y447383D02*
X75567Y446044D01*
G01X71716Y451762D02*
X73024Y449820D01*
G01X71380Y453341D02*
X71716Y451762D01*
G01X67388Y466348D02*
X70590Y451286D01*
G01X70434Y457794D02*
X70770Y456215D01*
G01X67388Y466348D02*
X70590Y451286D01*
G01X68613Y466359D02*
X69823Y460667D01*
G01X67388Y466348D02*
X70590Y451286D01*
G01X68921Y467943D02*
X68613Y466359D01*
G01X70095Y480268D02*
X67388Y466348D01*
G01X69790Y472411D02*
X69482Y470827D01*
G01X70095Y480268D02*
X67388Y466348D01*
G01X71227Y479799D02*
X70351Y475295D01*
G01X70095Y480268D02*
X67388Y466348D01*
G01X74665Y447383D02*
X75567Y446044D01*
G01X71716Y451762D02*
X73024Y449820D01*
G01X71380Y453341D02*
X71716Y451762D01*
G01X67388Y466348D02*
X70590Y451286D01*
G01X70434Y457794D02*
X70770Y456215D01*
G01X67388Y466348D02*
X70590Y451286D01*
G01X68613Y466359D02*
X69823Y460667D01*
G01X67388Y466348D02*
X70590Y451286D01*
G01X68921Y467943D02*
X68613Y466359D01*
G01X70095Y480268D02*
X67388Y466348D01*
G01X69790Y472411D02*
X69482Y470827D01*
G01X70095Y480268D02*
X67388Y466348D01*
G01X71227Y479799D02*
X70351Y475295D01*
G01X70095Y480268D02*
X67388Y466348D01*
G01X74665Y447383D02*
X75567Y446044D01*
G01X71716Y451762D02*
X73024Y449820D01*
G01X67388Y466348D02*
X70590Y451286D01*
G01X71380Y453341D02*
X71716Y451762D01*
G01X70434Y457794D02*
X70770Y456215D01*
G01X68613Y466359D02*
X69823Y460667D01*
G01X70095Y480268D02*
X67388Y466348D01*
G01X68921Y467943D02*
X68613Y466359D01*
G01X69790Y472411D02*
X69482Y470827D01*
G01X71227Y479799D02*
X70351Y475295D01*
G01X74665Y447383D02*
X75567Y446044D01*
G01X71716Y451762D02*
X73024Y449820D01*
G01X67388Y466348D02*
X70590Y451286D01*
G01X71380Y453341D02*
X71716Y451762D01*
G01X70434Y457794D02*
X70770Y456215D01*
G01X68613Y466359D02*
X69823Y460667D01*
G01X70095Y480268D02*
X67388Y466348D01*
G01X68921Y467943D02*
X68613Y466359D01*
G01X69790Y472411D02*
X69482Y470827D01*
G01X71227Y479799D02*
X70351Y475295D01*
G01X75857Y478725D02*
G02X76759Y480379I3260J-705D01*
G01X77608Y479530D02*
G03X77031Y478471I1510J-1509D01*
G01X73446Y467554D02*
X75857Y478725D01*
G01X77031Y478471D02*
X74646Y467425D01*
G01X73446Y466671D02*
Y467554D01*
G01X74646Y467425D02*
Y466728D01*
G01X73593Y465114D02*
X73446Y466671D01*
G01X74646Y466728D02*
X74782Y465296D01*
G01X75241Y457361D02*
X73593Y465114D01*
G01X74782Y465296D02*
X76415Y457610D01*
G01X76233Y454964D02*
G02X75241Y457361I5967J3873D01*
G01X76415Y457610D02*
G03X77240Y455618I5785J1229D01*
G01D02*
X83746Y445602D01*
G01X77240Y455618D02*
X83746Y445602D01*
G01X76415Y457610D02*
G03X77240Y455618I5785J1229D01*
G01X76233Y454964D02*
G02X75241Y457361I5967J3873D01*
G01X74782Y465296D02*
X76415Y457610D01*
G01X75241Y457361D02*
X73593Y465114D01*
G01X74646Y466728D02*
X74782Y465296D01*
G01X73593Y465114D02*
X73446Y466671D01*
G01X74646Y467425D02*
Y466728D01*
G01X73446Y466671D02*
Y467554D01*
G01X77031Y478471D02*
X74646Y467425D01*
G01X73446Y467554D02*
X75857Y478725D01*
G01X77608Y479530D02*
G03X77031Y478471I1510J-1509D01*
G01X75857Y478725D02*
G02X76759Y480379I3260J-705D01*
G01X85490Y488389D02*
X86620D01*
G01X86550Y487189D02*
X85490D01*
G01X84260Y487880D02*
G02X85490Y488389I1229J-1230D01*
G01Y487189D02*
G03X85109Y487031I0J-538D01*
G01X76759Y480379D02*
X84260Y487880D01*
G01X85109Y487031D02*
X77608Y479530D01*
G01X85109Y487031D02*
X77608Y479530D01*
G01X76759Y480379D02*
X84260Y487880D01*
G01X85490Y487189D02*
G03X85109Y487031I0J-538D01*
G01X84260Y487880D02*
G02X85490Y488389I1229J-1230D01*
G01X86550Y487189D02*
X85490D01*
G01Y488389D02*
X86620D01*
G01X75916Y486752D02*
X71227Y479799D01*
G01X75056Y487624D02*
X70095Y480268D01*
G01X77266Y487636D02*
X75916Y486752D01*
G01X87560Y495807D02*
X75056Y487624D01*
G01X81139Y490170D02*
X79725Y489245D01*
G01X87560Y495807D02*
X75056Y487624D01*
G01X87918Y494607D02*
X83597Y491779D01*
G01X87560Y495807D02*
X75056Y487624D01*
G01X89532Y494607D02*
X87918D01*
G01X96360Y495807D02*
X87560D01*
G01X96360Y494607D02*
X92470D01*
G01X96360Y495807D02*
X87560D01*
G01X75056Y487624D02*
X70095Y480268D01*
G01X75916Y486752D02*
X71227Y479799D01*
G01X87560Y495807D02*
X75056Y487624D01*
G01X77266Y487636D02*
X75916Y486752D01*
G01X81139Y490170D02*
X79725Y489245D01*
G01X87918Y494607D02*
X83597Y491779D01*
G01X96360Y495807D02*
X87560D01*
G01X89532Y494607D02*
X87918D01*
G01X96360D02*
X92470D01*
G01X91235Y489504D02*
X104748D01*
G01X95149Y488304D02*
X93535D01*
G01X95149D02*
X93535D01*
G01X91235Y489504D02*
X104748D01*
G01X91235D02*
X104748D01*
G01X91235D02*
X104748D01*
G01X90740Y481100D02*
G03X89235Y480654I0J-2762D01*
G01X90740Y482300D02*
G03X88581Y481661I-1J-3963D01*
G01X98417Y481100D02*
X90740D01*
G01X98188Y482300D02*
X90740D01*
G01D02*
G03X88581Y481661I-1J-3963D01*
G01X90740Y481100D02*
G03X89235Y480654I0J-2762D01*
G01X98188Y482300D02*
X90740D01*
G01X98417Y481100D02*
X90740D01*
G01X75916Y486752D02*
X71227Y479799D01*
G01X75056Y487624D02*
X70095Y480268D01*
G01X77266Y487636D02*
X75916Y486752D01*
G01X87560Y495807D02*
X75056Y487624D01*
G01X81139Y490170D02*
X79725Y489245D01*
G01X87560Y495807D02*
X75056Y487624D01*
G01X87918Y494607D02*
X83597Y491779D01*
G01X87560Y495807D02*
X75056Y487624D01*
G01X89532Y494607D02*
X87918D01*
G01X96360Y495807D02*
X87560D01*
G01X96360Y494607D02*
X92470D01*
G01X96360Y495807D02*
X87560D01*
G01X75916Y486752D02*
X71227Y479799D01*
G01X75056Y487624D02*
X70095Y480268D01*
G01X77266Y487636D02*
X75916Y486752D01*
G01X87560Y495807D02*
X75056Y487624D01*
G01X81139Y490170D02*
X79725Y489245D01*
G01X87560Y495807D02*
X75056Y487624D01*
G01X87918Y494607D02*
X83597Y491779D01*
G01X87560Y495807D02*
X75056Y487624D01*
G01X89532Y494607D02*
X87918D01*
G01X96360Y495807D02*
X87560D01*
G01X96360Y494607D02*
X92470D01*
G01X96360Y495807D02*
X87560D01*
G01X75056Y487624D02*
X70095Y480268D01*
G01X75916Y486752D02*
X71227Y479799D01*
G01X87560Y495807D02*
X75056Y487624D01*
G01X77266Y487636D02*
X75916Y486752D01*
G01X81139Y490170D02*
X79725Y489245D01*
G01X87918Y494607D02*
X83597Y491779D01*
G01X96360Y495807D02*
X87560D01*
G01X89532Y494607D02*
X87918D01*
G01X96360D02*
X92470D01*
G01X75056Y487624D02*
X70095Y480268D01*
G01X75916Y486752D02*
X71227Y479799D01*
G01X87560Y495807D02*
X75056Y487624D01*
G01X77266Y487636D02*
X75916Y486752D01*
G01X81139Y490170D02*
X79725Y489245D01*
G01X87918Y494607D02*
X83597Y491779D01*
G01X96360Y495807D02*
X87560D01*
G01X89532Y494607D02*
X87918D01*
G01X96360D02*
X92470D01*
G01X85490Y488389D02*
X86620D01*
G01X86550Y487189D02*
X85490D01*
G01X84260Y487880D02*
G02X85490Y488389I1229J-1230D01*
G01Y487189D02*
G03X85109Y487031I0J-538D01*
G01X76759Y480379D02*
X84260Y487880D01*
G01X85109Y487031D02*
X77608Y479530D01*
G01X85109Y487031D02*
X77608Y479530D01*
G01X76759Y480379D02*
X84260Y487880D01*
G01X85490Y487189D02*
G03X85109Y487031I0J-538D01*
G01X84260Y487880D02*
G02X85490Y488389I1229J-1230D01*
G01X86550Y487189D02*
X85490D01*
G01Y488389D02*
X86620D01*
G01X111397Y420217D02*
X111674Y419939D01*
G01X110546Y419369D02*
X110825Y419090D01*
G01X111241Y420594D02*
G03X111397Y420217I534J0D01*
G01X110041Y420594D02*
G03X110546Y419369I1734J-2D01*
G01X111241Y427882D02*
Y420594D01*
G01X110041Y427384D02*
Y420594D01*
G01X109893Y429230D02*
X111241Y427882D01*
G01X109395Y428030D02*
X110041Y427384D01*
G01X108802Y429230D02*
X109893D01*
G01X108634Y428030D02*
X109395D01*
G01X110546Y419369D02*
X110825Y419090D01*
G01X111397Y420217D02*
X111674Y419939D01*
G01X110041Y420594D02*
G03X110546Y419369I1734J-2D01*
G01X111241Y420594D02*
G03X111397Y420217I534J0D01*
G01X110041Y427384D02*
Y420594D01*
G01X111241Y427882D02*
Y420594D01*
G01X109395Y428030D02*
X110041Y427384D01*
G01X109893Y429230D02*
X111241Y427882D01*
G01X108634Y428030D02*
X109395D01*
G01X108802Y429230D02*
X109893D01*
G01X101516Y429240D02*
X102932D01*
G01X101352Y428040D02*
X103072D01*
G01X101352D02*
X103072D01*
G01X101516Y429240D02*
X102932D01*
G01X111397Y420217D02*
X111674Y419939D01*
G01X110546Y419369D02*
X110825Y419090D01*
G01X111241Y420594D02*
G03X111397Y420217I534J0D01*
G01X110041Y420594D02*
G03X110546Y419369I1734J-2D01*
G01X111241Y427882D02*
Y420594D01*
G01X110041Y427384D02*
Y420594D01*
G01X109893Y429230D02*
X111241Y427882D01*
G01X109395Y428030D02*
X110041Y427384D01*
G01X108802Y429230D02*
X109893D01*
G01X108634Y428030D02*
X109395D01*
G01X110546Y419369D02*
X110825Y419090D01*
G01X111397Y420217D02*
X111674Y419939D01*
G01X110041Y420594D02*
G03X110546Y419369I1734J-2D01*
G01X111241Y420594D02*
G03X111397Y420217I534J0D01*
G01X110041Y427384D02*
Y420594D01*
G01X111241Y427882D02*
Y420594D01*
G01X109395Y428030D02*
X110041Y427384D01*
G01X109893Y429230D02*
X111241Y427882D01*
G01X108634Y428030D02*
X109395D01*
G01X108802Y429230D02*
X109893D01*
G01X101516Y429240D02*
X102932D01*
G01X101352Y428040D02*
X103072D01*
G01X101516Y429240D02*
X102932D01*
G01X101352Y428040D02*
X103072D01*
G01X101352D02*
X103072D01*
G01X101516Y429240D02*
X102932D01*
G01X101352Y428040D02*
X103072D01*
G01X101516Y429240D02*
X102932D01*
G01X113566Y497866D02*
X117100D01*
G01X116299Y496666D02*
X114064D01*
G01X105527Y489827D02*
X113566Y497866D01*
G01X107555Y490157D02*
X106376Y488978D01*
G01X108757Y490157D02*
X107555D01*
G01X110759Y493361D02*
X109618Y492220D01*
G01X111961Y493361D02*
X110759D01*
G01X114064Y496666D02*
X112823Y495425D01*
G01X104748Y489504D02*
G03X105527Y489827I0J1101D01*
G01X106376Y488978D02*
G02X104748Y488304I-1627J1627D01*
G01X99853D02*
X98239D01*
G01X104748D02*
X102943D01*
G01X99853D02*
X98239D01*
G01X104748D02*
X102943D01*
G01X106376Y488978D02*
G02X104748Y488304I-1627J1627D01*
G01Y489504D02*
G03X105527Y489827I0J1101D01*
G01X107555Y490157D02*
X106376Y488978D01*
G01X105527Y489827D02*
X113566Y497866D01*
G01X108757Y490157D02*
X107555D01*
G01X105527Y489827D02*
X113566Y497866D01*
G01X110759Y493361D02*
X109618Y492220D01*
G01X105527Y489827D02*
X113566Y497866D01*
G01X111961Y493361D02*
X110759D01*
G01X105527Y489827D02*
X113566Y497866D01*
G01X114064Y496666D02*
X112823Y495425D01*
G01X105527Y489827D02*
X113566Y497866D01*
G01X116299Y496666D02*
X114064D01*
G01X113566Y497866D02*
X117100D01*
G01X105476Y483895D02*
X98417Y481100D01*
G01X104940Y484974D02*
X98188Y482300D01*
G01X108140Y485509D02*
X105476Y483895D01*
G01X107518Y486536D02*
X104940Y484974D01*
G01X110769Y487570D02*
G02X108140Y485509I-9826J9827D01*
G01X109920Y488419D02*
G02X107518Y486536I-8977J8978D01*
G01X116160Y492961D02*
X110769Y487570D01*
G01X115805Y494305D02*
X109920Y488419D01*
G01X104940Y484974D02*
X98188Y482300D01*
G01X105476Y483895D02*
X98417Y481100D01*
G01X107518Y486536D02*
X104940Y484974D01*
G01X108140Y485509D02*
X105476Y483895D01*
G01X109920Y488419D02*
G02X107518Y486536I-8977J8978D01*
G01X110769Y487570D02*
G02X108140Y485509I-9826J9827D01*
G01X115805Y494305D02*
X109920Y488419D01*
G01X116160Y492961D02*
X110769Y487570D01*
G01X105850Y562900D02*
X104430D01*
G01X104510Y564100D02*
X105850D01*
G01X104510D02*
X105850D01*
G01Y562900D02*
X104430D01*
G01X105850D02*
X104430D01*
G01X104510Y564100D02*
X105850D01*
G01X104510D02*
X105850D01*
G01Y562900D02*
X104430D01*
G01X105850D02*
X104430D01*
G01X104510Y564100D02*
X105850D01*
G01X104510D02*
X105850D01*
G01Y562900D02*
X104430D01*
G01X121700Y548202D02*
Y547100D01*
G01X122900Y547700D02*
Y548700D01*
G01X119533Y550369D02*
X121700Y548202D01*
G01X122900Y548700D02*
X117232Y554368D01*
G01X116384Y553517D02*
X117525Y552376D01*
G01X122900Y548700D02*
X117232Y554368D01*
G01X115300Y556134D02*
G03X116384Y553517I3700J0D01*
G01X117232Y554368D02*
G02X116500Y556136I1768J1768D01*
G01X115300Y559600D02*
Y556134D01*
G01X116500Y556136D02*
Y559601D01*
G01X114309Y561991D02*
G02X115300Y559600I-2391J-2392D01*
G01X116500Y559601D02*
G03X115158Y562840I-4582J-1D01*
G01X113546Y562754D02*
X114299Y562000D01*
G01X115158Y562840D02*
X114395Y563604D01*
G01X113193Y562900D02*
G02X113546Y562754I0J-500D01*
G01X114395Y563604D02*
G03X113193Y564100I-1200J-1204D01*
G01X112300Y562900D02*
X113193D01*
G01Y564100D02*
X112300D01*
G01X113193D02*
X112300D01*
G01Y562900D02*
X113193D01*
G01X114395Y563604D02*
G03X113193Y564100I-1200J-1204D01*
G01Y562900D02*
G02X113546Y562754I0J-500D01*
G01X115158Y562840D02*
X114395Y563604D01*
G01X113546Y562754D02*
X114299Y562000D01*
G01X116500Y559601D02*
G03X115158Y562840I-4582J-1D01*
G01X114309Y561991D02*
G02X115300Y559600I-2391J-2392D01*
G01X116500Y556136D02*
Y559601D01*
G01X115300Y559600D02*
Y556134D01*
G01X117232Y554368D02*
G02X116500Y556136I1768J1768D01*
G01X115300Y556134D02*
G03X116384Y553517I3700J0D01*
G01X122900Y548700D02*
X117232Y554368D01*
G01X119533Y550369D02*
X121700Y548202D01*
G01X116384Y553517D02*
X117525Y552376D01*
G01X122900Y547700D02*
Y548700D01*
G01X121700Y548202D02*
Y547100D01*
G01X154330Y173810D02*
Y176278D01*
G01X153130Y175780D02*
Y170531D01*
G01X154330Y165458D02*
Y167330D01*
G01X153130Y170531D02*
Y165458D01*
G01X153744Y164044D02*
G03X154330Y165458I-1413J1414D01*
G01X153130D02*
G02X152895Y164893I-799J1D01*
G01X148886Y159186D02*
X153744Y164044D01*
G01X152895Y164893D02*
X148037Y160035D01*
G01X148300Y157772D02*
G02X148886Y159186I1999J0D01*
G01X148037Y160035D02*
G03X147100Y157772I2262J-2262D01*
G01X148300Y154977D02*
Y157772D01*
G01X147100D02*
Y156876D01*
G01Y157772D02*
Y156876D01*
G01X148300Y154977D02*
Y157772D01*
G01X148037Y160035D02*
G03X147100Y157772I2262J-2262D01*
G01X148300D02*
G02X148886Y159186I1999J0D01*
G01X152895Y164893D02*
X148037Y160035D01*
G01X148886Y159186D02*
X153744Y164044D01*
G01X153130Y165458D02*
G02X152895Y164893I-799J1D01*
G01X153744Y164044D02*
G03X154330Y165458I-1413J1414D01*
G01X153130Y170531D02*
Y165458D01*
G01X154330D02*
Y167330D01*
G01X153130Y175780D02*
Y170531D01*
G01X154330Y173810D02*
Y176278D01*
G01Y173810D02*
Y176278D01*
G01X153130Y175780D02*
Y170531D01*
G01X154330Y165458D02*
Y167330D01*
G01X153130Y170531D02*
Y165458D01*
G01X153744Y164044D02*
G03X154330Y165458I-1413J1414D01*
G01X153130D02*
G02X152895Y164893I-799J1D01*
G01X148886Y159186D02*
X153744Y164044D01*
G01X152895Y164893D02*
X148037Y160035D01*
G01X148300Y157772D02*
G02X148886Y159186I1999J0D01*
G01X148037Y160035D02*
G03X147100Y157772I2262J-2262D01*
G01X148300Y154977D02*
Y157772D01*
G01X147100D02*
Y156876D01*
G01X154330Y173810D02*
Y176278D01*
G01X153130Y175780D02*
Y170531D01*
G01X154330Y165458D02*
Y167330D01*
G01X153130Y170531D02*
Y165458D01*
G01X153744Y164044D02*
G03X154330Y165458I-1413J1414D01*
G01X153130D02*
G02X152895Y164893I-799J1D01*
G01X148886Y159186D02*
X153744Y164044D01*
G01X152895Y164893D02*
X148037Y160035D01*
G01X148300Y157772D02*
G02X148886Y159186I1999J0D01*
G01X148037Y160035D02*
G03X147100Y157772I2262J-2262D01*
G01X148300Y154977D02*
Y157772D01*
G01X147100D02*
Y156876D01*
G01Y157772D02*
Y156876D01*
G01X148300Y154977D02*
Y157772D01*
G01X148037Y160035D02*
G03X147100Y157772I2262J-2262D01*
G01X148300D02*
G02X148886Y159186I1999J0D01*
G01X152895Y164893D02*
X148037Y160035D01*
G01X148886Y159186D02*
X153744Y164044D01*
G01X153130Y165458D02*
G02X152895Y164893I-799J1D01*
G01X153744Y164044D02*
G03X154330Y165458I-1413J1414D01*
G01X153130Y170531D02*
Y165458D01*
G01X154330D02*
Y167330D01*
G01X153130Y175780D02*
Y170531D01*
G01X154330Y173810D02*
Y176278D01*
G01X147100Y157772D02*
Y156876D01*
G01X148300Y154977D02*
Y157772D01*
G01X148037Y160035D02*
G03X147100Y157772I2262J-2262D01*
G01X148300D02*
G02X148886Y159186I1999J0D01*
G01X152895Y164893D02*
X148037Y160035D01*
G01X148886Y159186D02*
X153744Y164044D01*
G01X153130Y165458D02*
G02X152895Y164893I-799J1D01*
G01X153744Y164044D02*
G03X154330Y165458I-1413J1414D01*
G01X153130Y170531D02*
Y165458D01*
G01X154330D02*
Y167330D01*
G01X153130Y175780D02*
Y170531D01*
G01X154330Y173810D02*
Y176278D01*
G01D02*
X153130Y177478D01*
G01X151199Y177711D02*
X153130Y175780D01*
G01X160194Y183586D02*
X163772D01*
G01Y184786D02*
X160692D01*
G01X157560Y186220D02*
X160194Y183586D01*
G01X160692Y184786D02*
X158058Y187420D01*
G01X154280Y186220D02*
X157560D01*
G01X158058Y187420D02*
X153782D01*
G01X153130Y185070D02*
X154280Y186220D01*
G01X153782Y187420D02*
X151199Y184837D01*
G01Y177711D02*
X153130Y175780D01*
G01X154330Y176278D02*
X153130Y177478D01*
G01X153782Y187420D02*
X151199Y184837D01*
G01X153130Y185070D02*
X154280Y186220D01*
G01X158058Y187420D02*
X153782D01*
G01X154280Y186220D02*
X157560D01*
G01X160692Y184786D02*
X158058Y187420D01*
G01X157560Y186220D02*
X160194Y183586D01*
G01X163772Y184786D02*
X160692D01*
G01X160194Y183586D02*
X163772D01*
G01X154330Y176278D02*
X153130Y177478D01*
G01X151199Y177711D02*
X153130Y175780D01*
G01X160194Y183586D02*
X163772D01*
G01Y184786D02*
X160692D01*
G01X157560Y186220D02*
X160194Y183586D01*
G01X160692Y184786D02*
X158058Y187420D01*
G01X154280Y186220D02*
X157560D01*
G01X158058Y187420D02*
X153782D01*
G01X153130Y185070D02*
X154280Y186220D01*
G01X153782Y187420D02*
X151199Y184837D01*
G01X154330Y176278D02*
X153130Y177478D01*
G01X151199Y177711D02*
X153130Y175780D01*
G01X160194Y183586D02*
X163772D01*
G01Y184786D02*
X160692D01*
G01X157560Y186220D02*
X160194Y183586D01*
G01X160692Y184786D02*
X158058Y187420D01*
G01X154280Y186220D02*
X157560D01*
G01X158058Y187420D02*
X153782D01*
G01X153130Y185070D02*
X154280Y186220D01*
G01X153782Y187420D02*
X151199Y184837D01*
G01Y177711D02*
X153130Y175780D01*
G01X154330Y176278D02*
X153130Y177478D01*
G01X153782Y187420D02*
X151199Y184837D01*
G01X153130Y185070D02*
X154280Y186220D01*
G01X158058Y187420D02*
X153782D01*
G01X154280Y186220D02*
X157560D01*
G01X160692Y184786D02*
X158058Y187420D01*
G01X157560Y186220D02*
X160194Y183586D01*
G01X163772Y184786D02*
X160692D01*
G01X160194Y183586D02*
X163772D01*
G01X151199Y177711D02*
X153130Y175780D01*
G01X154330Y176278D02*
X153130Y177478D01*
G01X153782Y187420D02*
X151199Y184837D01*
G01X153130Y185070D02*
X154280Y186220D01*
G01X158058Y187420D02*
X153782D01*
G01X154280Y186220D02*
X157560D01*
G01X160692Y184786D02*
X158058Y187420D01*
G01X157560Y186220D02*
X160194Y183586D01*
G01X163772Y184786D02*
X160692D01*
G01X160194Y183586D02*
X163772D01*
G01X180314D02*
X177796D01*
G01X180812Y184786D02*
X177796D01*
G01X181200Y182700D02*
X180314Y183586D01*
G01X181698Y183900D02*
X180812Y184786D01*
G01X206152Y182700D02*
X181200D01*
G01X187592Y183900D02*
X181698D01*
G01X192044D02*
X190430D01*
G01X196496D02*
X194882D01*
G01X180812Y184786D02*
X177796D01*
G01X180314Y183586D02*
X177796D01*
G01X181698Y183900D02*
X180812Y184786D01*
G01X181200Y182700D02*
X180314Y183586D01*
G01X187592Y183900D02*
X181698D01*
G01X206152Y182700D02*
X181200D01*
G01X192044Y183900D02*
X190430D01*
G01X206152Y182700D02*
X181200D01*
G01X196496Y183900D02*
X194882D01*
G01X206152Y182700D02*
X181200D01*
G01X206152D02*
X181200D01*
G01X206152D02*
X181200D01*
G01X184973Y506115D02*
X183359D01*
G01X204585Y507315D02*
X182481D01*
G01X189505Y506115D02*
X187891D01*
G01X204585Y507315D02*
X182481D01*
G01X194037Y506115D02*
X192423D01*
G01X204585Y507315D02*
X182481D01*
G01X204087Y506115D02*
X196955D01*
G01X204585Y507315D02*
X182481D01*
G01X204585D02*
X182481D01*
G01X184973Y506115D02*
X183359D01*
G01X189505D02*
X187891D01*
G01X194037D02*
X192423D01*
G01X204087D02*
X196955D01*
G01X181631Y833067D02*
X229556Y785142D01*
G01X180431Y832569D02*
X228707Y784293D01*
G01X180431Y832569D02*
X228707Y784293D01*
G01X181631Y833067D02*
X229556Y785142D01*
G01X181631Y833067D02*
X229556Y785142D01*
G01X180431Y832569D02*
X228707Y784293D01*
G01X180431Y832569D02*
X228707Y784293D01*
G01X181631Y833067D02*
X229556Y785142D01*
G01X181631Y877417D02*
Y833067D01*
G01X180431Y877418D02*
Y832569D01*
G01Y877418D02*
Y832569D01*
G01X181631Y877417D02*
Y833067D01*
G01X191895Y832800D02*
Y831800D01*
G01X193095Y832800D02*
Y831848D01*
G01Y832800D02*
Y831848D01*
G01X191895Y832800D02*
Y831800D01*
G01X191920Y882407D02*
Y841431D01*
G01X193121Y882416D02*
Y841428D01*
G01Y882416D02*
Y841428D01*
G01X191920Y882407D02*
Y841431D01*
G01X191895Y832800D02*
Y831800D01*
G01X193095Y832800D02*
Y831848D01*
G01Y832800D02*
Y831848D01*
G01X191895Y832800D02*
Y831800D01*
G01X181631Y877417D02*
Y833067D01*
G01X180431Y877418D02*
Y832569D01*
G01Y877418D02*
Y832569D01*
G01X181631Y877417D02*
Y833067D01*
G01X181924Y878124D02*
G03X181631Y877417I707J-707D01*
G01X181075Y878973D02*
G03X180431Y877418I1556J-1555D01*
G01X183027Y879227D02*
X181924Y878124D01*
G01X182178Y880076D02*
X181075Y878973D01*
G01X183671Y880782D02*
G02X183027Y879227I-2200J0D01*
G01X182471Y880783D02*
G02X182178Y880076I-1000J0D01*
G01X183671Y881964D02*
Y880782D01*
G01X182471Y882022D02*
Y880783D01*
G01X181075Y878973D02*
G03X180431Y877418I1556J-1555D01*
G01X181924Y878124D02*
G03X181631Y877417I707J-707D01*
G01X182178Y880076D02*
X181075Y878973D01*
G01X183027Y879227D02*
X181924Y878124D01*
G01X182471Y880783D02*
G02X182178Y880076I-1000J0D01*
G01X183671Y880782D02*
G02X183027Y879227I-2200J0D01*
G01X182471Y882022D02*
Y880783D01*
G01X183671Y881964D02*
Y880782D01*
G01X181924Y878124D02*
G03X181631Y877417I707J-707D01*
G01X181075Y878973D02*
G03X180431Y877418I1556J-1555D01*
G01X183027Y879227D02*
X181924Y878124D01*
G01X182178Y880076D02*
X181075Y878973D01*
G01X183671Y880782D02*
G02X183027Y879227I-2200J0D01*
G01X182471Y880783D02*
G02X182178Y880076I-1000J0D01*
G01X183671Y881964D02*
Y880782D01*
G01X182471Y882022D02*
Y880783D01*
G01X181075Y878973D02*
G03X180431Y877418I1556J-1555D01*
G01X181924Y878124D02*
G03X181631Y877417I707J-707D01*
G01X182178Y880076D02*
X181075Y878973D01*
G01X183027Y879227D02*
X181924Y878124D01*
G01X182471Y880783D02*
G02X182178Y880076I-1000J0D01*
G01X183671Y880782D02*
G02X183027Y879227I-2200J0D01*
G01X182471Y882022D02*
Y880783D01*
G01X183671Y881964D02*
Y880782D01*
G01X200948Y183900D02*
X199334D01*
G01X205654D02*
X203786D01*
G01X208681Y185229D02*
X206152Y182700D01*
G01X207481Y185727D02*
X205654Y183900D01*
G01X208681Y187307D02*
Y185229D01*
G01X207481Y187308D02*
Y185727D01*
G01X200948Y183900D02*
X199334D01*
G01X205654D02*
X203786D01*
G01X207481Y185727D02*
X205654Y183900D01*
G01X208681Y185229D02*
X206152Y182700D01*
G01X207481Y187308D02*
Y185727D01*
G01X208681Y187307D02*
Y185229D01*
G01X224623Y338175D02*
X236000Y349552D01*
G01X237200Y349054D02*
X225121Y336975D01*
G01X223160Y338175D02*
X224623D01*
G01X225121Y336975D02*
X222920D01*
G01X225121D02*
X222920D01*
G01X223160Y338175D02*
X224623D01*
G01X237200Y349054D02*
X225121Y336975D01*
G01X224623Y338175D02*
X236000Y349552D01*
G01X224623Y338175D02*
X236000Y349552D01*
G01X237200Y349054D02*
X225121Y336975D01*
G01X223160Y338175D02*
X224623D01*
G01X225121Y336975D02*
X222920D01*
G01X225121D02*
X222920D01*
G01X223160Y338175D02*
X224623D01*
G01X237200Y349054D02*
X225121Y336975D01*
G01X224623Y338175D02*
X236000Y349552D01*
G01X224623Y338175D02*
X236000Y349552D01*
G01X237200Y349054D02*
X225121Y336975D01*
G01X223160Y338175D02*
X224623D01*
G01X225121Y336975D02*
X222920D01*
G01X225121D02*
X222920D01*
G01X223160Y338175D02*
X224623D01*
G01X237200Y349054D02*
X225121Y336975D01*
G01X224623Y338175D02*
X236000Y349552D01*
G01X221164Y503331D02*
X214581D01*
G01X221662Y504531D02*
X214719D01*
G01X225257Y499238D02*
X221164Y503331D01*
G01X225755Y500438D02*
X221662Y504531D01*
G01X228238Y499238D02*
X225257D01*
G01X227740Y500438D02*
X225755D01*
G01X232300Y503300D02*
X228238Y499238D01*
G01X231802Y504500D02*
X227740Y500438D01*
G01X251675Y503300D02*
X232300D01*
G01X251177Y504500D02*
X231802D01*
G01X221662Y504531D02*
X214719D01*
G01X221164Y503331D02*
X214581D01*
G01X225755Y500438D02*
X221662Y504531D01*
G01X225257Y499238D02*
X221164Y503331D01*
G01X227740Y500438D02*
X225755D01*
G01X228238Y499238D02*
X225257D01*
G01X231802Y504500D02*
X227740Y500438D01*
G01X232300Y503300D02*
X228238Y499238D01*
G01X251177Y504500D02*
X231802D01*
G01X251675Y503300D02*
X232300D01*
G01X205402Y504800D02*
X204087Y506115D01*
G01X205900Y506000D02*
X204585Y507315D01*
G01X207091Y504800D02*
X205402D01*
G01X209750Y506000D02*
X205900D01*
G01D02*
X204585Y507315D01*
G01X205402Y504800D02*
X204087Y506115D01*
G01X209750Y506000D02*
X205900D01*
G01X207091Y504800D02*
X205402D01*
G01X230700Y782379D02*
Y775235D01*
G01X229500Y782379D02*
Y774625D01*
G01X229556Y785142D02*
G02X230700Y782379I-2763J-2762D01*
G01X228707Y784293D02*
G02X229500Y782379I-1913J-1914D01*
G01D02*
Y774625D01*
G01X230700Y782379D02*
Y775235D01*
G01X228707Y784293D02*
G02X229500Y782379I-1913J-1914D01*
G01X229556Y785142D02*
G02X230700Y782379I-2763J-2762D01*
G01D02*
Y775235D01*
G01X229500Y782379D02*
Y774625D01*
G01X229556Y785142D02*
G02X230700Y782379I-2763J-2762D01*
G01X228707Y784293D02*
G02X229500Y782379I-1913J-1914D01*
G01D02*
Y774625D01*
G01X230700Y782379D02*
Y775235D01*
G01X228707Y784293D02*
G02X229500Y782379I-1913J-1914D01*
G01X229556Y785142D02*
G02X230700Y782379I-2763J-2762D01*
G01X204493Y832800D02*
Y831900D01*
G01X205693Y832800D02*
Y831942D01*
G01X217092Y832800D02*
Y831822D01*
G01X218292Y832800D02*
Y831822D01*
G01X229690Y832800D02*
Y831817D01*
G01X230890Y832800D02*
Y831849D01*
G01X205693Y832800D02*
Y831942D01*
G01X204493Y832800D02*
Y831900D01*
G01X218292Y832800D02*
Y831822D01*
G01X217092Y832800D02*
Y831822D01*
G01X230890Y832800D02*
Y831849D01*
G01X229690Y832800D02*
Y831817D01*
G01X204518Y882407D02*
Y841431D01*
G01X205719Y882416D02*
Y841428D01*
G01X217117Y882407D02*
Y841431D01*
G01X218318Y882416D02*
Y841428D01*
G01X229715Y882407D02*
Y841431D01*
G01X230916Y882416D02*
Y841428D01*
G01X205719Y882416D02*
Y841428D01*
G01X204518Y882407D02*
Y841431D01*
G01X218318Y882416D02*
Y841428D01*
G01X217117Y882407D02*
Y841431D01*
G01X230916Y882416D02*
Y841428D01*
G01X229715Y882407D02*
Y841431D01*
G01X204493Y832800D02*
Y831900D01*
G01X205693Y832800D02*
Y831942D01*
G01X217092Y832800D02*
Y831822D01*
G01X218292Y832800D02*
Y831822D01*
G01X229690Y832800D02*
Y831817D01*
G01X230890Y832800D02*
Y831849D01*
G01X205693Y832800D02*
Y831942D01*
G01X204493Y832800D02*
Y831900D01*
G01X218292Y832800D02*
Y831822D01*
G01X217092Y832800D02*
Y831822D01*
G01X230890Y832800D02*
Y831849D01*
G01X229690Y832800D02*
Y831817D01*
G01X253300Y370248D02*
X290344D01*
G01X289846Y369048D02*
X253798D01*
G01X236000Y352948D02*
X253300Y370248D01*
G01X253798Y369048D02*
X237200Y352450D01*
G01X236000Y349552D02*
Y352948D01*
G01X237200Y352450D02*
Y349054D01*
G01Y352450D02*
Y349054D01*
G01X236000Y349552D02*
Y352948D01*
G01X253798Y369048D02*
X237200Y352450D01*
G01X236000Y352948D02*
X253300Y370248D01*
G01X289846Y369048D02*
X253798D01*
G01X253300Y370248D02*
X290344D01*
G01X253300D02*
X290344D01*
G01X289846Y369048D02*
X253798D01*
G01X236000Y352948D02*
X253300Y370248D01*
G01X253798Y369048D02*
X237200Y352450D01*
G01X236000Y349552D02*
Y352948D01*
G01X237200Y352450D02*
Y349054D01*
G01Y352450D02*
Y349054D01*
G01X236000Y349552D02*
Y352948D01*
G01X253798Y369048D02*
X237200Y352450D01*
G01X236000Y352948D02*
X253300Y370248D01*
G01X289846Y369048D02*
X253798D01*
G01X253300Y370248D02*
X290344D01*
G01X253300D02*
X290344D01*
G01X289846Y369048D02*
X253798D01*
G01X236000Y352948D02*
X253300Y370248D01*
G01X253798Y369048D02*
X237200Y352450D01*
G01X236000Y349552D02*
Y352948D01*
G01X237200Y352450D02*
Y349054D01*
G01Y352450D02*
Y349054D01*
G01X236000Y349552D02*
Y352948D01*
G01X253798Y369048D02*
X237200Y352450D01*
G01X236000Y352948D02*
X253300Y370248D01*
G01X289846Y369048D02*
X253798D01*
G01X253300Y370248D02*
X290344D01*
G01X253333Y504958D02*
X251675Y503300D01*
G01X252835Y506158D02*
X251177Y504500D01*
G01X257261Y504958D02*
X253333D01*
G01X257759Y506158D02*
X252835D01*
G01X258208Y504011D02*
X257261Y504958D01*
G01X259408Y504509D02*
X257759Y506158D01*
G01X258208Y503675D02*
Y504011D01*
G01X259408Y503673D02*
Y504509D01*
G01X252835Y506158D02*
X251177Y504500D01*
G01X253333Y504958D02*
X251675Y503300D01*
G01X257759Y506158D02*
X252835D01*
G01X257261Y504958D02*
X253333D01*
G01X259408Y504509D02*
X257759Y506158D01*
G01X258208Y504011D02*
X257261Y504958D01*
G01X259408Y503673D02*
Y504509D01*
G01X258208Y503675D02*
Y504011D01*
G01X251737Y832800D02*
Y831989D01*
G01X252937Y832800D02*
Y831989D01*
G01X264336Y831887D02*
G02X263904Y830844I-1475J0D01*
G01X265536Y831887D02*
G02Y831877I-2675J-5D01*
G01X264336Y832800D02*
Y831887D01*
G01X265536Y832800D02*
Y831887D01*
G01X252937Y832800D02*
Y831989D01*
G01X251737Y832800D02*
Y831989D01*
G01X265536Y831887D02*
G02Y831877I-2675J-5D01*
G01X264336Y831887D02*
G02X263904Y830844I-1475J0D01*
G01X265536Y832800D02*
Y831887D01*
G01X264336Y832800D02*
Y831887D01*
G01X251762Y882407D02*
Y841431D01*
G01X252963Y882416D02*
Y841428D01*
G01X264361Y882407D02*
Y841431D01*
G01X265562Y882416D02*
Y841428D01*
G01X252963Y882416D02*
Y841428D01*
G01X251762Y882407D02*
Y841431D01*
G01X265562Y882416D02*
Y841428D01*
G01X264361Y882407D02*
Y841431D01*
G01X251737Y832800D02*
Y831989D01*
G01X252937Y832800D02*
Y831989D01*
G01X264336Y831887D02*
G02X263904Y830844I-1475J0D01*
G01X265536Y831887D02*
G02Y831877I-2675J-5D01*
G01X264336Y832800D02*
Y831887D01*
G01X265536Y832800D02*
Y831887D01*
G01X252937Y832800D02*
Y831989D01*
G01X251737Y832800D02*
Y831989D01*
G01X265536Y831887D02*
G02Y831877I-2675J-5D01*
G01X264336Y831887D02*
G02X263904Y830844I-1475J0D01*
G01X265536Y832800D02*
Y831887D01*
G01X264336Y832800D02*
Y831887D01*
G01X292992Y367600D02*
X366100D01*
G01X365602Y366400D02*
X292494D01*
G01X290344Y370248D02*
X292992Y367600D01*
G01X292494Y366400D02*
X289846Y369048D01*
G01X292494Y366400D02*
X289846Y369048D01*
G01X290344Y370248D02*
X292992Y367600D01*
G01X365602Y366400D02*
X292494D01*
G01X292992Y367600D02*
X366100D01*
G01X292992D02*
X366100D01*
G01X365602Y366400D02*
X292494D01*
G01X290344Y370248D02*
X292992Y367600D01*
G01X292494Y366400D02*
X289846Y369048D01*
G01X292494Y366400D02*
X289846Y369048D01*
G01X290344Y370248D02*
X292992Y367600D01*
G01X365602Y366400D02*
X292494D01*
G01X292992Y367600D02*
X366100D01*
G01X292992D02*
X366100D01*
G01X365602Y366400D02*
X292494D01*
G01X290344Y370248D02*
X292992Y367600D01*
G01X292494Y366400D02*
X289846Y369048D01*
G01X292494Y366400D02*
X289846Y369048D01*
G01X290344Y370248D02*
X292992Y367600D01*
G01X365602Y366400D02*
X292494D01*
G01X292992Y367600D02*
X366100D01*
G01X276934Y832800D02*
Y831882D01*
G01X278134Y832800D02*
Y831944D01*
G01Y832800D02*
Y831944D01*
G01X276934Y832800D02*
Y831882D01*
G01X276959Y882407D02*
Y841431D01*
G01X278160Y882416D02*
Y841428D01*
G01Y882416D02*
Y841428D01*
G01X276959Y882407D02*
Y841431D01*
G01X276934Y832800D02*
Y831882D01*
G01X278134Y832800D02*
Y831944D01*
G01Y832800D02*
Y831944D01*
G01X276934Y832800D02*
Y831882D01*
G01X314729Y832800D02*
Y831700D01*
G01X315929Y832800D02*
Y831746D01*
G01X327328Y832800D02*
Y831900D01*
G01X328528Y832800D02*
Y831943D01*
G01X315929Y832800D02*
Y831746D01*
G01X314729Y832800D02*
Y831700D01*
G01X328528Y832800D02*
Y831943D01*
G01X327328Y832800D02*
Y831900D01*
G01X314754Y882407D02*
Y841431D01*
G01X315955Y882416D02*
Y841428D01*
G01X327353Y882407D02*
Y841431D01*
G01X328554Y882416D02*
Y841428D01*
G01X315955Y882416D02*
Y841428D01*
G01X314754Y882407D02*
Y841431D01*
G01X328554Y882416D02*
Y841428D01*
G01X327353Y882407D02*
Y841431D01*
G01X314729Y832800D02*
Y831700D01*
G01X315929Y832800D02*
Y831746D01*
G01X327328Y832800D02*
Y831900D01*
G01X328528Y832800D02*
Y831943D01*
G01X315929Y832800D02*
Y831746D01*
G01X314729Y832800D02*
Y831700D01*
G01X328528Y832800D02*
Y831943D01*
G01X327328Y832800D02*
Y831900D01*
G01X366100Y367600D02*
X387500Y346200D01*
G01X386300Y345702D02*
X365602Y366400D01*
G01X386300Y345702D02*
X365602Y366400D01*
G01X366100Y367600D02*
X387500Y346200D01*
G01X366100Y367600D02*
X387500Y346200D01*
G01X386300Y345702D02*
X365602Y366400D01*
G01X386300Y345702D02*
X365602Y366400D01*
G01X366100Y367600D02*
X387500Y346200D01*
G01X366100Y367600D02*
X387500Y346200D01*
G01X386300Y345702D02*
X365602Y366400D01*
G01X386300Y345702D02*
X365602Y366400D01*
G01X366100Y367600D02*
X387500Y346200D01*
G01X361414Y731782D02*
X361845Y731351D01*
G01X362263Y732631D02*
X362694Y732200D01*
G01X360904Y733012D02*
G03X361414Y731782I1740J1D01*
G01X362104Y733013D02*
G03X362263Y732631I540J0D01*
G01X360904Y735024D02*
Y733012D01*
G01X362104Y734918D02*
Y733013D01*
G01X363342Y748848D02*
X360904Y735024D01*
G01X364478Y748378D02*
X362104Y734918D01*
G01X377831Y769540D02*
X363342Y748848D01*
G01X378693Y768678D02*
X364478Y748378D01*
G01X362263Y732631D02*
X362694Y732200D01*
G01X361414Y731782D02*
X361845Y731351D01*
G01X362104Y733013D02*
G03X362263Y732631I540J0D01*
G01X360904Y733012D02*
G03X361414Y731782I1740J1D01*
G01X362104Y734918D02*
Y733013D01*
G01X360904Y735024D02*
Y733012D01*
G01X364478Y748378D02*
X362104Y734918D01*
G01X363342Y748848D02*
X360904Y735024D01*
G01X378693Y768678D02*
X364478Y748378D01*
G01X377831Y769540D02*
X363342Y748848D01*
G01X361414Y731782D02*
X361845Y731351D01*
G01X362263Y732631D02*
X362694Y732200D01*
G01X360904Y733012D02*
G03X361414Y731782I1740J1D01*
G01X362104Y733013D02*
G03X362263Y732631I540J0D01*
G01X360904Y735024D02*
Y733012D01*
G01X362104Y734918D02*
Y733013D01*
G01X363342Y748848D02*
X360904Y735024D01*
G01X364478Y748378D02*
X362104Y734918D01*
G01X377831Y769540D02*
X363342Y748848D01*
G01X378693Y768678D02*
X364478Y748378D01*
G01X362263Y732631D02*
X362694Y732200D01*
G01X361414Y731782D02*
X361845Y731351D01*
G01X362104Y733013D02*
G03X362263Y732631I540J0D01*
G01X360904Y733012D02*
G03X361414Y731782I1740J1D01*
G01X362104Y734918D02*
Y733013D01*
G01X360904Y735024D02*
Y733012D01*
G01X364478Y748378D02*
X362104Y734918D01*
G01X363342Y748848D02*
X360904Y735024D01*
G01X378693Y768678D02*
X364478Y748378D01*
G01X377831Y769540D02*
X363342Y748848D01*
G01X339926Y832800D02*
Y831900D01*
G01X341126Y832800D02*
Y831943D01*
G01X352525Y832800D02*
Y832025D01*
G01X353725Y832800D02*
Y832025D01*
G01X365123Y832800D02*
Y831923D01*
G01X366323Y832800D02*
Y831924D01*
G01X341126Y832800D02*
Y831943D01*
G01X339926Y832800D02*
Y831900D01*
G01X353725Y832800D02*
Y832025D01*
G01X352525Y832800D02*
Y832025D01*
G01X366323Y832800D02*
Y831924D01*
G01X365123Y832800D02*
Y831923D01*
G01X339951Y882407D02*
Y841431D01*
G01X341152Y882416D02*
Y841428D01*
G01X352550Y882407D02*
Y841431D01*
G01X353751Y882416D02*
Y841428D01*
G01X365148Y882407D02*
Y841431D01*
G01X366349Y882416D02*
Y841428D01*
G01X341152Y882416D02*
Y841428D01*
G01X339951Y882407D02*
Y841431D01*
G01X353751Y882416D02*
Y841428D01*
G01X352550Y882407D02*
Y841431D01*
G01X366349Y882416D02*
Y841428D01*
G01X365148Y882407D02*
Y841431D01*
G01X339926Y832800D02*
Y831900D01*
G01X341126Y832800D02*
Y831943D01*
G01X352525Y832800D02*
Y832025D01*
G01X353725Y832800D02*
Y832025D01*
G01X365123Y832800D02*
Y831923D01*
G01X366323Y832800D02*
Y831924D01*
G01X341126Y832800D02*
Y831943D01*
G01X339926Y832800D02*
Y831900D01*
G01X353725Y832800D02*
Y832025D01*
G01X352525Y832800D02*
Y832025D01*
G01X366323Y832800D02*
Y831924D01*
G01X365123Y832800D02*
Y831923D01*
G01X393100Y321700D02*
X402644D01*
G01X402440Y320500D02*
X392602D01*
G01X387500Y327300D02*
X393100Y321700D01*
G01X392602Y320500D02*
X386300Y326802D01*
G01X387500Y346200D02*
Y327300D01*
G01X386300Y326802D02*
Y345702D01*
G01Y326802D02*
Y345702D01*
G01X387500Y346200D02*
Y327300D01*
G01X392602Y320500D02*
X386300Y326802D01*
G01X387500Y327300D02*
X393100Y321700D01*
G01X402440Y320500D02*
X392602D01*
G01X393100Y321700D02*
X402644D01*
G01X393100D02*
X402644D01*
G01X402440Y320500D02*
X392602D01*
G01X387500Y327300D02*
X393100Y321700D01*
G01X392602Y320500D02*
X386300Y326802D01*
G01X387500Y346200D02*
Y327300D01*
G01X386300Y326802D02*
Y345702D01*
G01Y326802D02*
Y345702D01*
G01X387500Y346200D02*
Y327300D01*
G01X392602Y320500D02*
X386300Y326802D01*
G01X387500Y327300D02*
X393100Y321700D01*
G01X402440Y320500D02*
X392602D01*
G01X393100Y321700D02*
X402644D01*
G01X393100D02*
X402644D01*
G01X402440Y320500D02*
X392602D01*
G01X387500Y327300D02*
X393100Y321700D01*
G01X392602Y320500D02*
X386300Y326802D01*
G01X387500Y346200D02*
Y327300D01*
G01X386300Y326802D02*
Y345702D01*
G01Y326802D02*
Y345702D01*
G01X387500Y346200D02*
Y327300D01*
G01X392602Y320500D02*
X386300Y326802D01*
G01X387500Y327300D02*
X393100Y321700D01*
G01X402440Y320500D02*
X392602D01*
G01X393100Y321700D02*
X402644D01*
G01X409133Y791458D02*
X377831Y769540D01*
G01X409995Y790596D02*
X378693Y768678D01*
G01X409995Y790596D02*
X378693Y768678D01*
G01X409133Y791458D02*
X377831Y769540D01*
G01X409133Y791458D02*
X377831Y769540D01*
G01X409995Y790596D02*
X378693Y768678D01*
G01X409995Y790596D02*
X378693Y768678D01*
G01X409133Y791458D02*
X377831Y769540D01*
G01X387171Y832800D02*
Y831800D01*
G01X388371Y832800D02*
Y831848D01*
G01X399769Y831867D02*
G02X399351Y830858I-1427J0D01*
G01X400969Y831867D02*
G02Y831818I-2627J-25D01*
G01X399769Y832800D02*
Y831867D01*
G01X400969Y832800D02*
Y831867D01*
G01X388371Y832800D02*
Y831848D01*
G01X387171Y832800D02*
Y831800D01*
G01X400969Y831867D02*
G02Y831818I-2627J-25D01*
G01X399769Y831867D02*
G02X399351Y830858I-1427J0D01*
G01X400969Y832800D02*
Y831867D01*
G01X399769Y832800D02*
Y831867D01*
G01X387196Y882407D02*
Y841431D01*
G01X388397Y882416D02*
Y841428D01*
G01X399794Y882407D02*
Y841431D01*
G01X400995Y882416D02*
Y841428D01*
G01X388397Y882416D02*
Y841428D01*
G01X387196Y882407D02*
Y841431D01*
G01X400995Y882416D02*
Y841428D01*
G01X399794Y882407D02*
Y841431D01*
G01X387171Y832800D02*
Y831800D01*
G01X388371Y832800D02*
Y831848D01*
G01X399769Y831867D02*
G02X399351Y830858I-1427J0D01*
G01X400969Y831867D02*
G02Y831818I-2627J-25D01*
G01X399769Y832800D02*
Y831867D01*
G01X400969Y832800D02*
Y831867D01*
G01X388371Y832800D02*
Y831848D01*
G01X387171Y832800D02*
Y831800D01*
G01X400969Y831867D02*
G02Y831818I-2627J-25D01*
G01X399769Y831867D02*
G02X399351Y830858I-1427J0D01*
G01X400969Y832800D02*
Y831867D01*
G01X399769Y832800D02*
Y831867D01*
G01X432632Y825017D02*
X409133Y791458D01*
G01X433615Y824328D02*
X409995Y790596D01*
G01X433615Y824328D02*
X409995Y790596D01*
G01X432632Y825017D02*
X409133Y791458D01*
G01X432632Y825017D02*
X409133Y791458D01*
G01X433615Y824328D02*
X409995Y790596D01*
G01X433615Y824328D02*
X409995Y790596D01*
G01X432632Y825017D02*
X409133Y791458D01*
G01X434440Y830753D02*
G02X432632Y825017I-10000J-1D01*
G01X435640Y830752D02*
G02X433615Y824328I-11200J-1D01*
G01X434440Y873300D02*
Y830753D01*
G01X435640Y830752D02*
G02X433615Y824328I-11200J-1D01*
G01X434440Y830753D02*
G02X432632Y825017I-10000J-1D01*
G01X434440Y873300D02*
Y830753D01*
G01X412368Y831864D02*
G02X411952Y830860I-1420J0D01*
G01X413568Y831864D02*
G02Y831854I-2620J-5D01*
G01X412368Y832800D02*
Y831864D01*
G01X413568Y832800D02*
Y831864D01*
G01X424966Y832800D02*
Y831982D01*
G01X426166Y832800D02*
Y832046D01*
G01X413568Y831864D02*
G02Y831854I-2620J-5D01*
G01X412368Y831864D02*
G02X411952Y830860I-1420J0D01*
G01X413568Y832800D02*
Y831864D01*
G01X412368Y832800D02*
Y831864D01*
G01X426166Y832800D02*
Y832046D01*
G01X424966Y832800D02*
Y831982D01*
G01X412393Y882407D02*
Y841431D01*
G01X413594Y882416D02*
Y841428D01*
G01X424991Y882407D02*
Y841431D01*
G01X426192Y882416D02*
Y841428D01*
G01X413594Y882416D02*
Y841428D01*
G01X412393Y882407D02*
Y841431D01*
G01X426192Y882416D02*
Y841428D01*
G01X424991Y882407D02*
Y841431D01*
G01X412368Y831864D02*
G02X411952Y830860I-1420J0D01*
G01X413568Y831864D02*
G02Y831854I-2620J-5D01*
G01X412368Y832800D02*
Y831864D01*
G01X413568Y832800D02*
Y831864D01*
G01X424966Y832800D02*
Y831982D01*
G01X426166Y832800D02*
Y832046D01*
G01X413568Y831864D02*
G02Y831854I-2620J-5D01*
G01X412368Y831864D02*
G02X411952Y830860I-1420J0D01*
G01X413568Y832800D02*
Y831864D01*
G01X412368Y832800D02*
Y831864D01*
G01X426166Y832800D02*
Y832046D01*
G01X424966Y832800D02*
Y831982D01*
G01X434440Y830753D02*
G02X432632Y825017I-10000J-1D01*
G01X435640Y830752D02*
G02X433615Y824328I-11200J-1D01*
G01X434440Y873300D02*
Y830753D01*
G01X435640Y830752D02*
G02X433615Y824328I-11200J-1D01*
G01X434440Y830753D02*
G02X432632Y825017I-10000J-1D01*
G01X434440Y873300D02*
Y830753D01*
G01X434439Y882407D02*
Y873301D01*
G01Y882407D02*
Y873301D01*
G01Y882407D02*
Y873301D01*
G01Y882407D02*
Y873301D01*
G01X435640Y882416D02*
Y830752D01*
G01Y882416D02*
Y830752D01*
G01Y882416D02*
Y830752D01*
G01Y882416D02*
Y830752D01*
G01Y882416D02*
Y830752D01*
G01Y882416D02*
Y830752D01*
G01X501705Y136504D02*
Y141995D01*
G01X501573Y124527D02*
Y128700D01*
G01X506490Y119610D02*
G02X501573Y124527I0J4917D01*
G01X501705Y136504D02*
Y141995D01*
G01X501573Y124527D02*
Y128700D01*
G01X506490Y119610D02*
G02X501573Y124527I0J4917D01*
G01X501705Y136504D02*
Y141995D01*
G01Y136504D02*
Y141995D01*
G01Y136504D02*
Y141995D01*
G01Y136504D02*
Y141995D01*
G01D02*
G02X502452Y143800I2552J1D01*
G01D02*
X505037Y146385D01*
G01X502452Y143800D02*
X505037Y146385D01*
G01X501705Y141995D02*
G02X502452Y143800I2552J1D01*
G01X501705Y141995D02*
G02X502452Y143800I2552J1D01*
G01D02*
X505037Y146385D01*
G01X502452Y143800D02*
X505037Y146385D01*
G01X501705Y141995D02*
G02X502452Y143800I2552J1D01*
G01X501705Y141995D02*
G02X502452Y143800I2552J1D01*
G01D02*
X505037Y146385D01*
G01X502452Y143800D02*
X505037Y146385D01*
G01X501705Y141995D02*
G02X502452Y143800I2552J1D01*
G01X535847Y99077D02*
G03X535239Y98240I2863J-2719D01*
G01X536021Y99391D02*
G02X535847Y99077I-1571J665D01*
G01X536099Y99624D02*
G02X536021Y99391I-1653J424D01*
G01X536154Y100052D02*
G02X536100Y99626I-1707J0D01*
G01X536154Y103000D02*
Y100052D01*
G01X535686Y105044D02*
G02X536154Y103000I-4230J-2044D01*
G01X534778Y106322D02*
G02X535686Y105044I-3322J-3322D01*
G01X536767Y105567D02*
G03X535629Y107169I-5298J-2558D01*
G01X518084Y123016D02*
X534778Y106322D01*
G01X535629Y107169D02*
X518933Y123865D01*
G01X535640Y83672D02*
G03X535583Y83582I4557J-2949D01*
G01X536351Y84548D02*
G03X535640Y83672I3836J-3840D01*
G01X535629Y107169D02*
X518933Y123865D01*
G01X518084Y123016D02*
X534778Y106322D01*
G01X536767Y105567D02*
G03X535629Y107169I-5298J-2558D01*
G01X534778Y106322D02*
G02X535686Y105044I-3322J-3322D01*
G01D02*
G02X536154Y103000I-4230J-2044D01*
G01D02*
Y100052D01*
G01X536099Y99624D02*
G02X536021Y99391I-1653J424D01*
G01X536154Y100052D02*
G02X536100Y99626I-1707J0D01*
G01X536021Y99391D02*
G02X535847Y99077I-1571J665D01*
G01X536099Y99624D02*
G02X536021Y99391I-1653J424D01*
G01X536154Y100052D02*
G02X536100Y99626I-1707J0D01*
G01X536021Y99391D02*
G02X535847Y99077I-1571J665D01*
G01X536099Y99624D02*
G02X536021Y99391I-1653J424D01*
G01X535847Y99077D02*
G03X535239Y98240I2863J-2719D01*
G01X535640Y83672D02*
G03X535583Y83582I4557J-2949D01*
G01X536351Y84548D02*
G03X535640Y83672I3836J-3840D01*
G01D02*
G03X535583Y83582I4557J-2949D01*
G01X536351Y84548D02*
G03X535640Y83672I3836J-3840D01*
G01X527658Y102852D02*
X510625Y119885D01*
G01X526809Y102003D02*
X509776Y119036D01*
G01X527884Y98278D02*
G03X527658Y102852I-2638J2162D01*
G01X526956Y99040D02*
G03X526809Y102003I-1710J1400D01*
G01X527403Y97607D02*
X527870Y98261D01*
G01X526380Y98240D02*
X526917Y98993D01*
G01X526809Y102003D02*
X509776Y119036D01*
G01X527658Y102852D02*
X510625Y119885D01*
G01X526956Y99040D02*
G03X526809Y102003I-1710J1400D01*
G01X527884Y98278D02*
G03X527658Y102852I-2638J2162D01*
G01X526380Y98240D02*
X526917Y98993D01*
G01X527403Y97607D02*
X527870Y98261D01*
G01X527574Y138234D02*
G03X527977Y139207I-973J973D01*
G01X528423Y137385D02*
G03X529175Y139101I-1822J1821D01*
G01X526208Y136868D02*
X527574Y138234D01*
G01X527057Y136019D02*
X528423Y137385D01*
G01X525600Y135400D02*
G02X526208Y136868I2076J0D01*
G01X526800Y135400D02*
G02X527057Y136019I876J-1D01*
G01X517100Y137871D02*
Y135590D01*
G01X518300Y137871D02*
Y135590D01*
G01X536032Y141482D02*
X537497Y142947D01*
G01X534100Y139715D02*
G02X535184Y142332I3700J0D01*
G01X535300Y139714D02*
G02X536032Y141482I2500J0D01*
G01X534100Y135734D02*
Y139715D01*
G01X535300Y135734D02*
Y139714D01*
G01X528423Y137385D02*
G03X529175Y139101I-1822J1821D01*
G01X527574Y138234D02*
G03X527977Y139207I-973J973D01*
G01X527057Y136019D02*
X528423Y137385D01*
G01X526208Y136868D02*
X527574Y138234D01*
G01X526800Y135400D02*
G02X527057Y136019I876J-1D01*
G01X525600Y135400D02*
G02X526208Y136868I2076J0D01*
G01X518300Y137871D02*
Y135590D01*
G01X517100Y137871D02*
Y135590D01*
G01X536032Y141482D02*
X537497Y142947D01*
G01X535300Y139714D02*
G02X536032Y141482I2500J0D01*
G01X534100Y139715D02*
G02X535184Y142332I3700J0D01*
G01X535300Y135734D02*
Y139714D01*
G01X534100Y135734D02*
Y139715D01*
G01X502905Y141995D02*
Y136515D01*
G01X526496Y121183D02*
X544004Y103677D01*
G01X544853Y104526D02*
X527345Y122032D01*
G01X525600Y123349D02*
G03X526496Y121183I3062J-2D01*
G01X527345Y122032D02*
G02X526800Y123349I1317J1316D01*
G01X525600Y128400D02*
Y123349D01*
G01X526800D02*
Y128400D01*
G01Y123349D02*
Y128400D01*
G01X525600D02*
Y123349D01*
G01X527345Y122032D02*
G02X526800Y123349I1317J1316D01*
G01X525600D02*
G03X526496Y121183I3062J-2D01*
G01X544853Y104526D02*
X527345Y122032D01*
G01X526496Y121183D02*
X544004Y103677D01*
G01X527574Y138234D02*
G03X527977Y139207I-973J973D01*
G01X528423Y137385D02*
G03X529175Y139101I-1822J1821D01*
G01X526208Y136868D02*
X527574Y138234D01*
G01X527057Y136019D02*
X528423Y137385D01*
G01X525600Y135400D02*
G02X526208Y136868I2076J0D01*
G01X526800Y135400D02*
G02X527057Y136019I876J-1D01*
G01X517100Y137871D02*
Y135590D01*
G01X518300Y137871D02*
Y135590D01*
G01X536032Y141482D02*
X537497Y142947D01*
G01X534100Y139715D02*
G02X535184Y142332I3700J0D01*
G01X535300Y139714D02*
G02X536032Y141482I2500J0D01*
G01X534100Y135734D02*
Y139715D01*
G01X535300Y135734D02*
Y139714D01*
G01X528423Y137385D02*
G03X529175Y139101I-1822J1821D01*
G01X527574Y138234D02*
G03X527977Y139207I-973J973D01*
G01X527057Y136019D02*
X528423Y137385D01*
G01X526208Y136868D02*
X527574Y138234D01*
G01X526800Y135400D02*
G02X527057Y136019I876J-1D01*
G01X525600Y135400D02*
G02X526208Y136868I2076J0D01*
G01X518300Y137871D02*
Y135590D01*
G01X517100Y137871D02*
Y135590D01*
G01X536032Y141482D02*
X537497Y142947D01*
G01X535300Y139714D02*
G02X536032Y141482I2500J0D01*
G01X534100Y139715D02*
G02X535184Y142332I3700J0D01*
G01X535300Y135734D02*
Y139714D01*
G01X534100Y135734D02*
Y139715D01*
G01X517100Y125395D02*
G03X518084Y123016I3364J-2D01*
G01X518933Y123865D02*
G02X518300Y125395I1530J1529D01*
G01X517100Y128400D02*
Y125395D01*
G01X518300D02*
Y128400D01*
G01X534922Y123062D02*
X550107Y107808D01*
G01X550958Y108655D02*
X535773Y123909D01*
G01X534100Y125054D02*
G03X534922Y123062I2823J-1D01*
G01X535773Y123909D02*
G02X535300Y125054I1149J1145D01*
G01X534100Y128400D02*
Y125054D01*
G01X535300D02*
Y128400D01*
G01X518300Y125395D02*
Y128400D01*
G01X517100D02*
Y125395D01*
G01X518933Y123865D02*
G02X518300Y125395I1530J1529D01*
G01X517100D02*
G03X518084Y123016I3364J-2D01*
G01X535300Y125054D02*
Y128400D01*
G01X534100D02*
Y125054D01*
G01X535773Y123909D02*
G02X535300Y125054I1149J1145D01*
G01X534100D02*
G03X534922Y123062I2823J-1D01*
G01X550958Y108655D02*
X535773Y123909D01*
G01X534922Y123062D02*
X550107Y107808D01*
G01X502773Y124527D02*
Y128700D01*
G01X506490Y120810D02*
G02X502773Y124527I0J3717D01*
G01X508390Y120810D02*
X506490D01*
G01X508391Y119610D02*
X506490D01*
G01X510625Y119885D02*
G03X508390Y120810I-2233J-2233D01*
G01X509776Y119036D02*
G03X508391Y119610I-1385J-1384D01*
G01X502905Y141995D02*
Y136515D01*
G01X502773Y124527D02*
Y128700D01*
G01X506490Y120810D02*
G02X502773Y124527I0J3717D01*
G01X508391Y119610D02*
X506490D01*
G01X508390Y120810D02*
X506490D01*
G01X509776Y119036D02*
G03X508391Y119610I-1385J-1384D01*
G01X510625Y119885D02*
G03X508390Y120810I-2233J-2233D01*
G01X502905Y141995D02*
Y136515D01*
G01Y141995D02*
Y136515D01*
G01Y141995D02*
Y136515D01*
G01Y141995D02*
Y136515D01*
G01X535184Y142332D02*
X536648Y143796D01*
G01X535184Y142332D02*
X536648Y143796D01*
G01X503301Y142951D02*
G03X502905Y141995I956J-956D01*
G01X505886Y145536D02*
X503301Y142951D01*
G01X507487Y146199D02*
G03X505886Y145536I0J-2264D01*
G01X505037Y146385D02*
G02X507487Y147399I2449J-2450D01*
G01X517559Y146199D02*
X507487D01*
G01X507488Y147399D02*
X517559D01*
G01X521197Y147705D02*
G02X517559Y146199I-3637J3639D01*
G01Y147399D02*
G03X520348Y148554I0J3945D01*
G01X521658Y148166D02*
X521197Y147705D01*
G01X520348Y148554D02*
X520809Y149015D01*
G01X522704Y150691D02*
G02X521658Y148166I-3572J1D01*
G01X520809Y149015D02*
G03X521504Y150692I-1677J1678D01*
G01X522704Y152875D02*
Y150691D01*
G01X521500Y151675D02*
Y164574D01*
G01X521504Y150692D02*
Y151675D01*
G01X522700Y164574D02*
Y152875D01*
G01X521500Y151675D02*
Y164574D01*
G01X522136Y165936D02*
G02X522700Y164574I-1363J-1362D01*
G01X521287Y165087D02*
G03X520774Y165300I-514J-513D01*
G01X521500Y164574D02*
G03X521287Y165087I-726J-1D01*
G01X520774Y166500D02*
G02X522136Y165936I0J-1927D01*
G01X521287Y165087D02*
G03X520774Y165300I-514J-513D01*
G01X521500Y164574D02*
G03X521287Y165087I-726J-1D01*
G01X520236Y166500D02*
X520774D01*
G01Y165300D02*
X520186D01*
G01X535184Y142332D02*
X536648Y143796D01*
G01X535184Y142332D02*
X536648Y143796D01*
G01X520774Y165300D02*
X520186D01*
G01X520236Y166500D02*
X520774D01*
G01X521287Y165087D02*
G03X520774Y165300I-514J-513D01*
G01X522136Y165936D02*
G02X522700Y164574I-1363J-1362D01*
G01X520774Y166500D02*
G02X522136Y165936I0J-1927D01*
G01X521500Y164574D02*
G03X521287Y165087I-726J-1D01*
G01X522136Y165936D02*
G02X522700Y164574I-1363J-1362D01*
G01X520774Y166500D02*
G02X522136Y165936I0J-1927D01*
G01X521500Y151675D02*
Y164574D01*
G01X522704Y152875D02*
Y150691D01*
G01X522700Y164574D02*
Y152875D01*
G01X521504Y150692D02*
Y151675D01*
G01X522704Y152875D02*
Y150691D01*
G01X520809Y149015D02*
G03X521504Y150692I-1677J1678D01*
G01X522704Y150691D02*
G02X521658Y148166I-3572J1D01*
G01X520348Y148554D02*
X520809Y149015D01*
G01X521658Y148166D02*
X521197Y147705D01*
G01X517559Y147399D02*
G03X520348Y148554I0J3945D01*
G01X521197Y147705D02*
G02X517559Y146199I-3637J3639D01*
G01X507488Y147399D02*
X517559D01*
G01Y146199D02*
X507487D01*
G01X505037Y146385D02*
G02X507487Y147399I2449J-2450D01*
G01Y146199D02*
G03X505886Y145536I0J-2264D01*
G01D02*
X503301Y142951D01*
G01D02*
G03X502905Y141995I956J-956D01*
G01X503301Y142951D02*
G03X502905Y141995I956J-956D01*
G01X505886Y145536D02*
X503301Y142951D01*
G01X507487Y146199D02*
G03X505886Y145536I0J-2264D01*
G01X505037Y146385D02*
G02X507487Y147399I2449J-2450D01*
G01X517559Y146199D02*
X507487D01*
G01X507488Y147399D02*
X517559D01*
G01X521197Y147705D02*
G02X517559Y146199I-3637J3639D01*
G01Y147399D02*
G03X520348Y148554I0J3945D01*
G01X521658Y148166D02*
X521197Y147705D01*
G01X520348Y148554D02*
X520809Y149015D01*
G01X522704Y150691D02*
G02X521658Y148166I-3572J1D01*
G01X520809Y149015D02*
G03X521504Y150692I-1677J1678D01*
G01X522704Y152875D02*
Y150691D01*
G01X521500Y151675D02*
Y164574D01*
G01X521504Y150692D02*
Y151675D01*
G01X522700Y164574D02*
Y152875D01*
G01X521500Y151675D02*
Y164574D01*
G01X522136Y165936D02*
G02X522700Y164574I-1363J-1362D01*
G01X521287Y165087D02*
G03X520774Y165300I-514J-513D01*
G01X521500Y164574D02*
G03X521287Y165087I-726J-1D01*
G01X520774Y166500D02*
G02X522136Y165936I0J-1927D01*
G01X521287Y165087D02*
G03X520774Y165300I-514J-513D01*
G01X521500Y164574D02*
G03X521287Y165087I-726J-1D01*
G01X520236Y166500D02*
X520774D01*
G01Y165300D02*
X520186D01*
G01X520774D02*
X520186D01*
G01X520236Y166500D02*
X520774D01*
G01X521287Y165087D02*
G03X520774Y165300I-514J-513D01*
G01X522136Y165936D02*
G02X522700Y164574I-1363J-1362D01*
G01X520774Y166500D02*
G02X522136Y165936I0J-1927D01*
G01X521500Y164574D02*
G03X521287Y165087I-726J-1D01*
G01X522136Y165936D02*
G02X522700Y164574I-1363J-1362D01*
G01X520774Y166500D02*
G02X522136Y165936I0J-1927D01*
G01X521500Y151675D02*
Y164574D01*
G01X522704Y152875D02*
Y150691D01*
G01X522700Y164574D02*
Y152875D01*
G01X521504Y150692D02*
Y151675D01*
G01X522704Y152875D02*
Y150691D01*
G01X520809Y149015D02*
G03X521504Y150692I-1677J1678D01*
G01X522704Y150691D02*
G02X521658Y148166I-3572J1D01*
G01X520348Y148554D02*
X520809Y149015D01*
G01X521658Y148166D02*
X521197Y147705D01*
G01X517559Y147399D02*
G03X520348Y148554I0J3945D01*
G01X521197Y147705D02*
G02X517559Y146199I-3637J3639D01*
G01X507488Y147399D02*
X517559D01*
G01Y146199D02*
X507487D01*
G01X505037Y146385D02*
G02X507487Y147399I2449J-2450D01*
G01Y146199D02*
G03X505886Y145536I0J-2264D01*
G01D02*
X503301Y142951D01*
G01D02*
G03X502905Y141995I956J-956D01*
G01X503301Y142951D02*
G03X502905Y141995I956J-956D01*
G01X505886Y145536D02*
X503301Y142951D01*
G01X507487Y146199D02*
G03X505886Y145536I0J-2264D01*
G01X505037Y146385D02*
G02X507487Y147399I2449J-2450D01*
G01X517559Y146199D02*
X507487D01*
G01X507488Y147399D02*
X517559D01*
G01X521197Y147705D02*
G02X517559Y146199I-3637J3639D01*
G01Y147399D02*
G03X520348Y148554I0J3945D01*
G01X521658Y148166D02*
X521197Y147705D01*
G01X520348Y148554D02*
X520809Y149015D01*
G01X522704Y150691D02*
G02X521658Y148166I-3572J1D01*
G01X520809Y149015D02*
G03X521504Y150692I-1677J1678D01*
G01X522704Y152875D02*
Y150691D01*
G01X521500Y151675D02*
Y164574D01*
G01X521504Y150692D02*
Y151675D01*
G01X522700Y164574D02*
Y152875D01*
G01X521500Y151675D02*
Y164574D01*
G01X522136Y165936D02*
G02X522700Y164574I-1363J-1362D01*
G01X521287Y165087D02*
G03X520774Y165300I-514J-513D01*
G01X521500Y164574D02*
G03X521287Y165087I-726J-1D01*
G01X520774Y166500D02*
G02X522136Y165936I0J-1927D01*
G01X521287Y165087D02*
G03X520774Y165300I-514J-513D01*
G01X521500Y164574D02*
G03X521287Y165087I-726J-1D01*
G01X520236Y166500D02*
X520774D01*
G01Y165300D02*
X520186D01*
G01X520774D02*
X520186D01*
G01X520236Y166500D02*
X520774D01*
G01X521287Y165087D02*
G03X520774Y165300I-514J-513D01*
G01X522136Y165936D02*
G02X522700Y164574I-1363J-1362D01*
G01X520774Y166500D02*
G02X522136Y165936I0J-1927D01*
G01X521500Y164574D02*
G03X521287Y165087I-726J-1D01*
G01X522136Y165936D02*
G02X522700Y164574I-1363J-1362D01*
G01X520774Y166500D02*
G02X522136Y165936I0J-1927D01*
G01X521500Y151675D02*
Y164574D01*
G01X522704Y152875D02*
Y150691D01*
G01X522700Y164574D02*
Y152875D01*
G01X521504Y150692D02*
Y151675D01*
G01X522704Y152875D02*
Y150691D01*
G01X520809Y149015D02*
G03X521504Y150692I-1677J1678D01*
G01X522704Y150691D02*
G02X521658Y148166I-3572J1D01*
G01X520348Y148554D02*
X520809Y149015D01*
G01X521658Y148166D02*
X521197Y147705D01*
G01X517559Y147399D02*
G03X520348Y148554I0J3945D01*
G01X521197Y147705D02*
G02X517559Y146199I-3637J3639D01*
G01X507488Y147399D02*
X517559D01*
G01Y146199D02*
X507487D01*
G01X505037Y146385D02*
G02X507487Y147399I2449J-2450D01*
G01Y146199D02*
G03X505886Y145536I0J-2264D01*
G01D02*
X503301Y142951D01*
G01D02*
G03X502905Y141995I956J-956D01*
G01X566036Y52025D02*
X567891D01*
G01X567200Y50825D02*
X566033D01*
G01X565637Y52057D02*
G03X566036Y52025I399J2469D01*
G01X566033Y50825D02*
G02X565446Y50872I0J3688D01*
G01X563519Y53138D02*
G03X565637Y52057I2737J2746D01*
G01X565446Y50872D02*
G02X562671Y52288I809J5012D01*
G01X562981Y53676D02*
X563519Y53138D01*
G01X562671Y52288D02*
X562132Y52827D01*
G01X562600Y54596D02*
G03X562981Y53676I1301J0D01*
G01X562132Y52827D02*
G02X561400Y54596I1770J1768D01*
G01X562600Y111210D02*
Y54596D01*
G01X561400D02*
Y111209D01*
G01Y54596D02*
Y111209D01*
G01X562600Y111210D02*
Y54596D01*
G01X562132Y52827D02*
G02X561400Y54596I1770J1768D01*
G01X562600D02*
G03X562981Y53676I1301J0D01*
G01X562671Y52288D02*
X562132Y52827D01*
G01X562981Y53676D02*
X563519Y53138D01*
G01X565446Y50872D02*
G02X562671Y52288I809J5012D01*
G01X563519Y53138D02*
G03X565637Y52057I2737J2746D01*
G01X566033Y50825D02*
G02X565446Y50872I0J3688D01*
G01X565637Y52057D02*
G03X566036Y52025I399J2469D01*
G01X567200Y50825D02*
X566033D01*
G01X566036Y52025D02*
X567891D01*
G01X556000Y107359D02*
G03X554887Y110045I-3800J-1D01*
G01X557200Y107360D02*
G03X555736Y110894I-5000J-1D01*
G01X556000Y93621D02*
Y107359D01*
G01X557200Y93621D02*
Y107360D01*
G01X554536Y90086D02*
G03X556000Y93621I-3536J3535D01*
G01X555385Y89237D02*
G03X557200Y93621I-4385J4383D01*
G01X553963Y89513D02*
X554536Y90086D01*
G01X554812Y88664D02*
X555385Y89237D01*
G01X552471Y88486D02*
G03X553963Y89513I-2042J4564D01*
G01X552962Y87390D02*
G03X554812Y88664I-2534J5659D01*
G01X550743Y87715D02*
X552471Y88486D01*
G01X551171Y86591D02*
X552962Y87390D01*
G01X547909Y86772D02*
X550736Y87711D01*
G01X548288Y85633D02*
X551171Y86591D01*
G01X546562Y85940D02*
G02X547909Y86772I2433J-2432D01*
G01X547411Y85091D02*
G02X548288Y85633I1584J-1583D01*
G01X544811Y84189D02*
X546562Y85940D01*
G01X545660Y83340D02*
X547411Y85091D01*
G01X544147Y83317D02*
G02X544811Y84189I3537J-2005D01*
G01X545192Y82725D02*
G02X545660Y83340I2493J-1412D01*
G01X544932Y82107D02*
G02X545192Y82725I2753J-795D01*
G01X557200Y107360D02*
G03X555736Y110894I-5000J-1D01*
G01X556000Y107359D02*
G03X554887Y110045I-3800J-1D01*
G01X557200Y93621D02*
Y107360D01*
G01X556000Y93621D02*
Y107359D01*
G01X555385Y89237D02*
G03X557200Y93621I-4385J4383D01*
G01X554536Y90086D02*
G03X556000Y93621I-3536J3535D01*
G01X554812Y88664D02*
X555385Y89237D01*
G01X553963Y89513D02*
X554536Y90086D01*
G01X552962Y87390D02*
G03X554812Y88664I-2534J5659D01*
G01X552471Y88486D02*
G03X553963Y89513I-2042J4564D01*
G01X551171Y86591D02*
X552962Y87390D01*
G01X550743Y87715D02*
X552471Y88486D01*
G01X548288Y85633D02*
X551171Y86591D01*
G01X547909Y86772D02*
X550736Y87711D01*
G01X547411Y85091D02*
G02X548288Y85633I1584J-1583D01*
G01X546562Y85940D02*
G02X547909Y86772I2433J-2432D01*
G01X545660Y83340D02*
X547411Y85091D01*
G01X544811Y84189D02*
X546562Y85940D01*
G01X545192Y82725D02*
G02X545660Y83340I2493J-1412D01*
G01X544147Y83317D02*
G02X544811Y84189I3537J-2005D01*
G01X544932Y82107D02*
G02X545192Y82725I2753J-795D01*
G01X544147Y83317D02*
G02X544811Y84189I3537J-2005D01*
G01X568295Y107467D02*
Y128342D01*
G01X567095Y107466D02*
Y128300D01*
G01X569027Y105699D02*
G02X568295Y107467I1768J1768D01*
G01X568179Y104849D02*
G02X567095Y107466I2616J2617D01*
G01X570367Y104359D02*
X569027Y105699D01*
G01X569519Y103509D02*
X568179Y104849D01*
G01X570251Y101741D02*
G03X569519Y103509I-2500J0D01*
G01X569860Y98575D02*
G03X570251Y99699I-1422J1125D01*
G01X569720Y98418D02*
G03X569860Y98575I-1281J1283D01*
G01X567095Y107466D02*
Y128300D01*
G01X568295Y107467D02*
Y128342D01*
G01X568179Y104849D02*
G02X567095Y107466I2616J2617D01*
G01X569027Y105699D02*
G02X568295Y107467I1768J1768D01*
G01X569519Y103509D02*
X568179Y104849D01*
G01X570367Y104359D02*
X569027Y105699D01*
G01X570251Y101741D02*
G03X569519Y103509I-2500J0D01*
G01X569860Y98575D02*
G03X570251Y99699I-1422J1125D01*
G01X569720Y98418D02*
G03X569860Y98575I-1281J1283D01*
G01X544383Y98716D02*
G03X543910Y98070I1839J-1843D01*
G01X544977Y97518D02*
G02X545232Y97867I1247J-643D01*
G01X544876Y97266D02*
G02X544977Y97518I1347J-394D01*
G01X544655Y99178D02*
G02X544383Y98716I-1022J291D01*
G01X545232Y97867D02*
G03X545810Y98852I-1600J1601D01*
G01X544782Y99893D02*
G02X544712Y99381I-1878J-4D01*
G01X545867Y99055D02*
G03X545983Y99894I-2962J837D01*
G01X544783Y101798D02*
Y99893D01*
G01X545983Y99894D02*
Y101799D01*
G01X544004Y103677D02*
G02X544783Y101798I-1879J-1880D01*
G01X545983Y101799D02*
G03X544853Y104526I-3858J-1D01*
G01X545983Y101799D02*
G03X544853Y104526I-3858J-1D01*
G01X544004Y103677D02*
G02X544783Y101798I-1879J-1880D01*
G01X545983Y99894D02*
Y101799D01*
G01X544783Y101798D02*
Y99893D01*
G01X545867Y99055D02*
G03X545983Y99894I-2962J837D01*
G01X544782Y99893D02*
G02X544712Y99381I-1878J-4D01*
G01X545232Y97867D02*
G03X545810Y98852I-1600J1601D01*
G01X544655Y99178D02*
G02X544383Y98716I-1022J291D01*
G01X544977Y97518D02*
G02X545232Y97867I1247J-643D01*
G01X544383Y98716D02*
G03X543910Y98070I1839J-1843D01*
G01X544876Y97266D02*
G02X544977Y97518I1347J-394D01*
G01X544383Y98716D02*
G03X543910Y98070I1839J-1843D01*
G01X536208Y97496D02*
G02X536767Y98300I2500J-1142D01*
G01X537128Y98927D02*
G03X537262Y99327I-2682J1121D01*
G01X536767Y98300D02*
G03X537128Y98927I-2319J1753D01*
G01X537262Y99327D02*
G03X537354Y100051I-2815J726D01*
G01X537128Y98927D02*
G03X537262Y99327I-2682J1121D01*
G01X536767Y98300D02*
G03X537128Y98927I-2319J1753D01*
G01X537262Y99327D02*
G03X537354Y100051I-2815J726D01*
G01X537128Y98927D02*
G03X537262Y99327I-2682J1121D01*
G01X537354Y100051D02*
Y103000D01*
G01D02*
G03X536767Y105567I-5899J2D01*
G01X536647Y83018D02*
G02X537200Y83699I3540J-2310D01*
G01X536544Y82851D02*
G02X536647Y83018I3649J-2135D01*
G01D02*
G02X537200Y83699I3540J-2310D01*
G01X536544Y82851D02*
G02X536647Y83018I3649J-2135D01*
G01X537353Y85552D02*
X536351Y84548D01*
G01X537200Y83699D02*
X538283Y84784D01*
G01X539175Y88236D02*
X537353Y85552D01*
G01X538283Y84784D02*
X540168Y87562D01*
G01X541665Y90123D02*
G03X539175Y88236I1542J-4620D01*
G01X540168Y87562D02*
G02X542045Y88984I3038J-2060D01*
G01X546297Y91665D02*
X541665Y90123D01*
G01X542045Y88984D02*
X546676Y90526D01*
G01X547449Y92377D02*
G02X546297Y91665I-2082J2080D01*
G01X546676Y90526D02*
G03X548298Y91527I-1307J3933D01*
G01X549391Y94318D02*
X547449Y92377D01*
G01X548298Y91527D02*
X550240Y93469D01*
G01X550861Y97282D02*
G02X549391Y94318I-5135J700D01*
G01X550240Y93469D02*
G03X552052Y97120I-4512J4515D01*
G01X550909Y97983D02*
G02X550861Y97282I-5182J3D01*
G01X550240Y93469D02*
G03X552052Y97120I-4512J4515D01*
G01X550910Y105866D02*
Y97982D01*
G01X552110Y97179D02*
Y105865D01*
G01X550107Y107808D02*
G02X550909Y105865I-1950J-1942D01*
G01X552110D02*
G03X550958Y108655I-3952J1D01*
G01X537354Y103000D02*
G03X536767Y105567I-5899J2D01*
G01X537354Y100051D02*
Y103000D01*
G01X537262Y99327D02*
G03X537354Y100051I-2815J726D01*
G01X537128Y98927D02*
G03X537262Y99327I-2682J1121D01*
G01X536767Y98300D02*
G03X537128Y98927I-2319J1753D01*
G01X536208Y97496D02*
G02X536767Y98300I2500J-1142D01*
G01X552110Y105865D02*
G03X550958Y108655I-3952J1D01*
G01X550107Y107808D02*
G02X550909Y105865I-1950J-1942D01*
G01X552110Y97179D02*
Y105865D01*
G01X550910Y105866D02*
Y97982D01*
G01X550240Y93469D02*
G03X552052Y97120I-4512J4515D01*
G01X550861Y97282D02*
G02X549391Y94318I-5135J700D01*
G01X550909Y97983D02*
G02X550861Y97282I-5182J3D01*
G01X548298Y91527D02*
X550240Y93469D01*
G01X549391Y94318D02*
X547449Y92377D01*
G01X546676Y90526D02*
G03X548298Y91527I-1307J3933D01*
G01X547449Y92377D02*
G02X546297Y91665I-2082J2080D01*
G01X542045Y88984D02*
X546676Y90526D01*
G01X546297Y91665D02*
X541665Y90123D01*
G01X540168Y87562D02*
G02X542045Y88984I3038J-2060D01*
G01X541665Y90123D02*
G03X539175Y88236I1542J-4620D01*
G01X538283Y84784D02*
X540168Y87562D01*
G01X539175Y88236D02*
X537353Y85552D01*
G01X537200Y83699D02*
X538283Y84784D01*
G01X537353Y85552D02*
X536351Y84548D01*
G01X536647Y83018D02*
G02X537200Y83699I3540J-2310D01*
G01X536544Y82851D02*
G02X536647Y83018I3649J-2135D01*
G01X542600Y135182D02*
Y136769D01*
G01X543800Y135553D02*
Y136544D01*
G01Y135553D02*
Y136544D01*
G01X542600Y135182D02*
Y136769D01*
G01Y135182D02*
Y136769D01*
G01X543800Y135553D02*
Y136544D01*
G01Y135553D02*
Y136544D01*
G01X542600Y135182D02*
Y136769D01*
G01Y124901D02*
Y128400D01*
G01X543800Y124901D02*
Y128400D01*
G01X544415Y120517D02*
G02X542600Y124901I4385J4383D01*
G01X545264Y121366D02*
G02X543800Y124901I3536J3535D01*
G01X554887Y110045D02*
X544415Y120517D01*
G01X555736Y110894D02*
X545264Y121366D01*
G01X543800Y124901D02*
Y128400D01*
G01X542600Y124901D02*
Y128400D01*
G01X545264Y121366D02*
G02X543800Y124901I3536J3535D01*
G01X544415Y120517D02*
G02X542600Y124901I4385J4383D01*
G01X555736Y110894D02*
X545264Y121366D01*
G01X554887Y110045D02*
X544415Y120517D01*
G01X561942Y112798D02*
G02X562600Y111210I-1588J-1588D01*
G01X561400Y111209D02*
G03X561093Y111949I-1045J0D01*
G01X556961Y117779D02*
X561942Y112798D01*
G01X561093Y111949D02*
X556112Y116930D01*
G01X556802Y118161D02*
G03X556961Y117779I540J0D01*
G01X556112Y116930D02*
G02X555602Y118160I1230J1231D01*
G01X556802Y132009D02*
Y118161D01*
G01X555602Y118160D02*
Y131801D01*
G01Y118160D02*
Y131801D01*
G01X556802Y132009D02*
Y118161D01*
G01X556112Y116930D02*
G02X555602Y118160I1230J1231D01*
G01X556802Y118161D02*
G03X556961Y117779I540J0D01*
G01X561093Y111949D02*
X556112Y116930D01*
G01X556961Y117779D02*
X561942Y112798D01*
G01X561400Y111209D02*
G03X561093Y111949I-1045J0D01*
G01X561942Y112798D02*
G02X562600Y111210I-1588J-1588D01*
G01X546403Y148686D02*
Y150940D01*
G01X547603Y148686D02*
Y150940D01*
G01X545931Y147548D02*
G03X546403Y148686I-1138J1139D01*
G01X546780Y146699D02*
G03X547603Y148686I-1987J1987D01*
G01X544086Y145703D02*
X545931Y147548D01*
G01X544935Y144854D02*
X546780Y146699D01*
G01X541787Y144750D02*
G03X544086Y145703I-1J3251D01*
G01X541787Y143550D02*
G03X544935Y144854I0J4452D01*
G01X538953Y144750D02*
X541787D01*
G01X538953Y143550D02*
X541787D01*
G01X536648Y143796D02*
G02X538953Y144750I2304J-2306D01*
G01X537497Y142947D02*
G02X538953Y143550I1456J-1456D01*
G01X547603Y148686D02*
Y150940D01*
G01X546403Y148686D02*
Y150940D01*
G01X546780Y146699D02*
G03X547603Y148686I-1987J1987D01*
G01X545931Y147548D02*
G03X546403Y148686I-1138J1139D01*
G01X544935Y144854D02*
X546780Y146699D01*
G01X544086Y145703D02*
X545931Y147548D01*
G01X541787Y143550D02*
G03X544935Y144854I0J4452D01*
G01X541787Y144750D02*
G03X544086Y145703I-1J3251D01*
G01X538953Y143550D02*
X541787D01*
G01X538953Y144750D02*
X541787D01*
G01X537497Y142947D02*
G02X538953Y143550I1456J-1456D01*
G01X536648Y143796D02*
G02X538953Y144750I2304J-2306D01*
G01X546403Y148686D02*
Y150940D01*
G01X547603Y148686D02*
Y150940D01*
G01X545931Y147548D02*
G03X546403Y148686I-1138J1139D01*
G01X546780Y146699D02*
G03X547603Y148686I-1987J1987D01*
G01X544086Y145703D02*
X545931Y147548D01*
G01X544935Y144854D02*
X546780Y146699D01*
G01X541787Y144750D02*
G03X544086Y145703I-1J3251D01*
G01X541787Y143550D02*
G03X544935Y144854I0J4452D01*
G01X538953Y144750D02*
X541787D01*
G01X538953Y143550D02*
X541787D01*
G01X536648Y143796D02*
G02X538953Y144750I2304J-2306D01*
G01X537497Y142947D02*
G02X538953Y143550I1456J-1456D01*
G01X547603Y148686D02*
Y150940D01*
G01X546403Y148686D02*
Y150940D01*
G01X546780Y146699D02*
G03X547603Y148686I-1987J1987D01*
G01X545931Y147548D02*
G03X546403Y148686I-1138J1139D01*
G01X544935Y144854D02*
X546780Y146699D01*
G01X544086Y145703D02*
X545931Y147548D01*
G01X541787Y143550D02*
G03X544935Y144854I0J4452D01*
G01X541787Y144750D02*
G03X544086Y145703I-1J3251D01*
G01X538953Y143550D02*
X541787D01*
G01X538953Y144750D02*
X541787D01*
G01X537497Y142947D02*
G02X538953Y143550I1456J-1456D01*
G01X536648Y143796D02*
G02X538953Y144750I2304J-2306D01*
G01X546226Y832800D02*
Y832100D01*
G01X547426Y832800D02*
Y831826D01*
G01X558825Y832800D02*
Y831700D01*
G01X560025Y832800D02*
Y831748D01*
G01X547426Y832800D02*
Y831826D01*
G01X546226Y832800D02*
Y832100D01*
G01X560025Y832800D02*
Y831748D01*
G01X558825Y832800D02*
Y831700D01*
G01X546251Y882407D02*
Y841431D01*
G01X547452Y882416D02*
Y841428D01*
G01X558850Y882407D02*
Y841431D01*
G01X560051Y882416D02*
Y841426D01*
G01X547452Y882416D02*
Y841428D01*
G01X546251Y882407D02*
Y841431D01*
G01X560051Y882416D02*
Y841426D01*
G01X558850Y882407D02*
Y841431D01*
G01X546226Y832800D02*
Y832100D01*
G01X547426Y832800D02*
Y831826D01*
G01X558825Y832800D02*
Y831700D01*
G01X560025Y832800D02*
Y831748D01*
G01X547426Y832800D02*
Y831826D01*
G01X546226Y832800D02*
Y832100D01*
G01X560025Y832800D02*
Y831748D01*
G01X558825Y832800D02*
Y831700D01*
G01X588650Y84848D02*
X586801Y82999D01*
G01X589500Y84000D02*
X589150Y83650D01*
G01X589775Y84276D02*
X589500Y84000D01*
G01X588925Y85125D02*
X588650Y84848D01*
G01X589500Y84000D02*
X589150Y83650D01*
G01X589775Y84276D02*
X589500Y84000D01*
G01X589783Y85698D02*
G03X588925Y85125I1015J-2448D01*
G01X590243Y84589D02*
G03X589775Y84276I556J-1338D01*
G01X590263Y84597D02*
G03X590243Y84589I528J-1350D01*
G01X590486Y85906D02*
G03X589835Y85719I498J-2961D01*
G01X590682Y84722D02*
G03X590294Y84610I303J-1777D01*
G01X591086Y86128D02*
G02X590517Y85911I-830J1322D01*
G01X591724Y85111D02*
G02X590712Y84726I-1469J2338D01*
G01X591569Y86513D02*
G02X591086Y86128I-1943J1942D01*
G01X592418Y85664D02*
G02X591724Y85111I-2791J2791D01*
G01X601218Y96162D02*
X591569Y86513D01*
G01X602066Y95312D02*
X592418Y85664D01*
G01X601950Y97930D02*
G02X601218Y96162I-2500J0D01*
G01X603150Y97929D02*
G02X602066Y95312I-3700J0D01*
G01X601950Y128500D02*
Y97930D01*
G01X603150Y128500D02*
Y97929D01*
G01X585650Y106586D02*
Y128600D01*
G01X586850D02*
Y106586D01*
G01X586382Y104818D02*
G02X585650Y106586I1769J1768D01*
G01X586850D02*
G03X587232Y105667I1300J2D01*
G01X587868Y103332D02*
X586382Y104818D01*
G01X587232Y105667D02*
X588717Y104181D01*
G01X588600Y101564D02*
G03X587868Y103332I-2501J0D01*
G01X588717Y104181D02*
G02X589800Y101564I-2618J-2616D01*
G01X588600Y100734D02*
Y101564D01*
G01X589800D02*
Y100734D01*
G01X587868Y98966D02*
G03X588600Y100734I-1769J1768D01*
G01X589800D02*
G02X588717Y98117I-3701J-1D01*
G01X579467Y99805D02*
X578374Y98144D01*
G01X579674Y97935D02*
X580470Y99145D01*
G01X579841Y100726D02*
G02X579467Y99805I-2501J479D01*
G01X580470Y99145D02*
G03X581020Y100501I-3130J2059D01*
G01X579949Y101292D02*
X579841Y100726D01*
G01X581020Y100501D02*
X581128Y101067D01*
G01X579960Y101405D02*
G02X579949Y101292I-601J1D01*
G01X581128Y101067D02*
G03X581160Y101405I-1769J338D01*
G01X579960Y119808D02*
Y101405D01*
G01X581160D02*
Y119809D01*
G01X594150Y96635D02*
Y128600D01*
G01X595350D02*
Y96634D01*
G01X593418Y94867D02*
G03X594150Y96635I-1768J1768D01*
G01X595350Y96634D02*
G02X594266Y94017I-3700J0D01*
G01X590814Y92263D02*
X593418Y94867D01*
G01X594266Y94017D02*
X591663Y91414D01*
G01X588202Y91181D02*
G03X590814Y92263I0J3694D01*
G01X591663Y91414D02*
G02X588203Y89981I-3460J3461D01*
G01X587599Y91181D02*
X588202D01*
G01X587594Y89981D02*
X586531Y89989D01*
G01X588203Y89981D02*
X587594D01*
G01X585100Y91200D02*
X587599Y91181D01*
G01X586531Y89989D02*
X585465Y89997D01*
G01X587594Y89981D02*
X586531Y89989D01*
G01X588203Y89981D02*
X587594D01*
G01X582600Y89500D02*
X585100Y91200D01*
G01X585465Y89997D02*
X583524Y88676D01*
G01X586531Y89989D02*
X585465Y89997D01*
G01X580501Y85499D02*
X582600Y89500D01*
G01X582504Y86731D02*
X581480Y84779D01*
G01X583524Y88676D02*
X582504Y86731D01*
G01X578151Y83149D02*
X580501Y85499D01*
G01X581150Y84450D02*
X580500Y83800D01*
G01X581480Y84779D02*
X581150Y84450D01*
G01X589500Y84000D02*
X589150Y83650D01*
G01X588650Y84848D02*
X586801Y82999D01*
G01X588925Y85125D02*
X588650Y84848D01*
G01X589775Y84276D02*
X589500Y84000D01*
G01X588650Y84848D02*
X586801Y82999D01*
G01X588925Y85125D02*
X588650Y84848D01*
G01X590243Y84589D02*
G03X589775Y84276I556J-1338D01*
G01X589783Y85698D02*
G03X588925Y85125I1015J-2448D01*
G01X590263Y84597D02*
G03X590243Y84589I528J-1350D01*
G01X589783Y85698D02*
G03X588925Y85125I1015J-2448D01*
G01X590682Y84722D02*
G03X590294Y84610I303J-1777D01*
G01X590486Y85906D02*
G03X589835Y85719I498J-2961D01*
G01X591724Y85111D02*
G02X590712Y84726I-1469J2338D01*
G01X591086Y86128D02*
G02X590517Y85911I-830J1322D01*
G01X592418Y85664D02*
G02X591724Y85111I-2791J2791D01*
G01X591569Y86513D02*
G02X591086Y86128I-1943J1942D01*
G01X602066Y95312D02*
X592418Y85664D01*
G01X601218Y96162D02*
X591569Y86513D01*
G01X603150Y97929D02*
G02X602066Y95312I-3700J0D01*
G01X601950Y97930D02*
G02X601218Y96162I-2500J0D01*
G01X603150Y128500D02*
Y97929D01*
G01X601950Y128500D02*
Y97930D01*
G01X589800Y100734D02*
G02X588717Y98117I-3701J-1D01*
G01X587868Y98966D02*
G03X588600Y100734I-1769J1768D01*
G01X589800Y101564D02*
Y100734D01*
G01X588600D02*
Y101564D01*
G01X588717Y104181D02*
G02X589800Y101564I-2618J-2616D01*
G01X588600D02*
G03X587868Y103332I-2501J0D01*
G01X587232Y105667D02*
X588717Y104181D01*
G01X587868Y103332D02*
X586382Y104818D01*
G01X586850Y106586D02*
G03X587232Y105667I1300J2D01*
G01X586382Y104818D02*
G02X585650Y106586I1769J1768D01*
G01X586850Y128600D02*
Y106586D01*
G01X585650D02*
Y128600D01*
G01X581160Y101405D02*
Y119809D01*
G01X579960Y119808D02*
Y101405D01*
G01X581128Y101067D02*
G03X581160Y101405I-1769J338D01*
G01X579960D02*
G02X579949Y101292I-601J1D01*
G01X581020Y100501D02*
X581128Y101067D01*
G01X579949Y101292D02*
X579841Y100726D01*
G01X580470Y99145D02*
G03X581020Y100501I-3130J2059D01*
G01X579841Y100726D02*
G02X579467Y99805I-2501J479D01*
G01X579674Y97935D02*
X580470Y99145D01*
G01X579467Y99805D02*
X578374Y98144D01*
G01X581150Y84450D02*
X580500Y83800D01*
G01X578151Y83149D02*
X580501Y85499D01*
G01X581480Y84779D02*
X581150Y84450D01*
G01X578151Y83149D02*
X580501Y85499D01*
G01X582504Y86731D02*
X581480Y84779D01*
G01X580501Y85499D02*
X582600Y89500D01*
G01X583524Y88676D02*
X582504Y86731D01*
G01X580501Y85499D02*
X582600Y89500D01*
G01X585465Y89997D02*
X583524Y88676D01*
G01X582600Y89500D02*
X585100Y91200D01*
G01X586531Y89989D02*
X585465Y89997D01*
G01X585100Y91200D02*
X587599Y91181D01*
G01X582600Y89500D02*
X585100Y91200D01*
G01X587594Y89981D02*
X586531Y89989D01*
G01X587599Y91181D02*
X588202D01*
G01X585100Y91200D02*
X587599Y91181D01*
G01X588203Y89981D02*
X587594D01*
G01X587599Y91181D02*
X588202D01*
G01X585100Y91200D02*
X587599Y91181D01*
G01X591663Y91414D02*
G02X588203Y89981I-3460J3461D01*
G01X588202Y91181D02*
G03X590814Y92263I0J3694D01*
G01X594266Y94017D02*
X591663Y91414D01*
G01X590814Y92263D02*
X593418Y94867D01*
G01X595350Y96634D02*
G02X594266Y94017I-3700J0D01*
G01X593418Y94867D02*
G03X594150Y96635I-1768J1768D01*
G01X595350Y128600D02*
Y96634D01*
G01X594150Y96635D02*
Y128600D01*
G01X571451Y101742D02*
G03X570367Y104359I-3700J0D01*
G01X571451Y99700D02*
Y101742D01*
G01X570251Y99699D02*
Y101741D01*
G01X570802Y97830D02*
G03X571451Y99700I-2365J1868D01*
G01Y101742D02*
G03X570367Y104359I-3700J0D01*
G01X570251Y99699D02*
Y101741D01*
G01X571451Y99700D02*
Y101742D01*
G01X570802Y97830D02*
G03X571451Y99700I-2365J1868D01*
G01X570802Y97830D02*
G03X571451Y99700I-2365J1868D01*
G01X595825Y141415D02*
G03X596300Y142562I-1147J1147D01*
G01X594150Y140268D02*
G02X594976Y142264I2823J1D01*
G01X595825Y141415D02*
G03X596300Y142562I-1147J1147D01*
G01X595350Y140268D02*
G02X595825Y141415I1622J0D01*
G01X594150Y136762D02*
Y140268D01*
G01X595350Y136762D02*
Y140268D01*
G01X595825Y141415D02*
G03X596300Y142562I-1147J1147D01*
G01X594150Y140268D02*
G02X594976Y142264I2823J1D01*
G01X595350Y140268D02*
G02X595825Y141415I1622J0D01*
G01X594150Y140268D02*
G02X594976Y142264I2823J1D01*
G01X595350Y136762D02*
Y140268D01*
G01X594150Y136762D02*
Y140268D01*
G01X602120Y135460D02*
Y136140D01*
G01X603320Y135460D02*
Y136140D01*
G01X585650Y135400D02*
Y136196D01*
G01X586850Y135500D02*
Y136196D01*
G01X575450Y135380D02*
Y136176D01*
G01X576650Y135380D02*
Y136176D01*
G01X603320Y135460D02*
Y136140D01*
G01X602120Y135460D02*
Y136140D01*
G01X586850Y135500D02*
Y136196D01*
G01X585650Y135400D02*
Y136196D01*
G01X576650Y135380D02*
Y136176D01*
G01X575450Y135380D02*
Y136176D01*
G01X602120Y135460D02*
Y136140D01*
G01X603320Y135460D02*
Y136140D01*
G01X585650Y135400D02*
Y136196D01*
G01X586850Y135500D02*
Y136196D01*
G01X575450Y135380D02*
Y136176D01*
G01X576650Y135380D02*
Y136176D01*
G01X595825Y141415D02*
G03X596300Y142562I-1147J1147D01*
G01X594150Y140268D02*
G02X594976Y142264I2823J1D01*
G01X595825Y141415D02*
G03X596300Y142562I-1147J1147D01*
G01X595350Y140268D02*
G02X595825Y141415I1622J0D01*
G01X594150Y136762D02*
Y140268D01*
G01X595350Y136762D02*
Y140268D01*
G01X603320Y135460D02*
Y136140D01*
G01X602120Y135460D02*
Y136140D01*
G01X586850Y135500D02*
Y136196D01*
G01X585650Y135400D02*
Y136196D01*
G01X576650Y135380D02*
Y136176D01*
G01X575450Y135380D02*
Y136176D01*
G01X595825Y141415D02*
G03X596300Y142562I-1147J1147D01*
G01X594150Y140268D02*
G02X594976Y142264I2823J1D01*
G01X595350Y140268D02*
G02X595825Y141415I1622J0D01*
G01X594150Y140268D02*
G02X594976Y142264I2823J1D01*
G01X595350Y136762D02*
Y140268D01*
G01X594150Y136762D02*
Y140268D01*
G01X579128Y121815D02*
G02X579960Y119808I-2009J-2009D01*
G01X581160Y119809D02*
G03X579977Y122664I-4041J-2D01*
G01X575380Y125563D02*
X579128Y121815D01*
G01X579977Y122664D02*
X576580Y126061D01*
G01X575380Y128500D02*
Y125563D01*
G01X576580Y126061D02*
Y128500D01*
G01Y126061D02*
Y128500D01*
G01X575380D02*
Y125563D01*
G01X579977Y122664D02*
X576580Y126061D01*
G01X575380Y125563D02*
X579128Y121815D01*
G01X581160Y119809D02*
G03X579977Y122664I-4041J-2D01*
G01X579128Y121815D02*
G02X579960Y119808I-2009J-2009D01*
G01X595100Y142562D02*
Y148000D01*
G01X596300Y142562D02*
Y147700D01*
G01X594976Y142264D02*
G03X595100Y142562I-298J299D01*
G01X596300D02*
Y147700D01*
G01X595100Y142562D02*
Y148000D01*
G01X594976Y142264D02*
G03X595100Y142562I-298J299D01*
G01D02*
Y148000D01*
G01X596300Y142562D02*
Y147700D01*
G01X594976Y142264D02*
G03X595100Y142562I-298J299D01*
G01X596300D02*
Y147700D01*
G01X595100Y142562D02*
Y148000D01*
G01X594976Y142264D02*
G03X595100Y142562I-298J299D01*
G01X596620Y832800D02*
Y831800D01*
G01X597820Y832800D02*
Y831799D01*
G01Y832800D02*
Y831799D01*
G01X596620Y832800D02*
Y831800D01*
G01X571423Y832800D02*
Y831923D01*
G01X572623Y832800D02*
Y831924D01*
G01X584021Y832800D02*
Y831821D01*
G01X585221Y832800D02*
Y831822D01*
G01X572623Y832800D02*
Y831924D01*
G01X571423Y832800D02*
Y831923D01*
G01X585221Y832800D02*
Y831822D01*
G01X584021Y832800D02*
Y831821D01*
G01X571448Y882407D02*
Y841431D01*
G01X572649Y882416D02*
Y841428D01*
G01X584046Y882407D02*
Y841431D01*
G01X585247Y882416D02*
Y841428D01*
G01X596645Y882407D02*
Y841431D01*
G01X597846Y882416D02*
Y841428D01*
G01X572649Y882416D02*
Y841428D01*
G01X571448Y882407D02*
Y841431D01*
G01X585247Y882416D02*
Y841428D01*
G01X584046Y882407D02*
Y841431D01*
G01X597846Y882416D02*
Y841428D01*
G01X596645Y882407D02*
Y841431D01*
G01X571423Y832800D02*
Y831923D01*
G01X572623Y832800D02*
Y831924D01*
G01X584021Y832800D02*
Y831821D01*
G01X585221Y832800D02*
Y831822D01*
G01X596620Y832800D02*
Y831800D01*
G01X597820Y832800D02*
Y831799D01*
G01X572623Y832800D02*
Y831924D01*
G01X571423Y832800D02*
Y831923D01*
G01X585221Y832800D02*
Y831822D01*
G01X584021Y832800D02*
Y831821D01*
G01X597820Y832800D02*
Y831799D01*
G01X596620Y832800D02*
Y831800D01*
G01X631951Y84749D02*
X630887Y83684D01*
G01X631778Y82878D02*
X632750Y83850D01*
G01X634318Y85700D02*
G03X632837Y85363I-1J-3419D01*
G01X633357Y84281D02*
G02X634319Y84500I961J-2000D01*
G01X632750Y83850D02*
G02X633357Y84281I1570J-1568D01*
G01X635300Y85700D02*
X634318D01*
G01X634319Y84500D02*
X635300D01*
G01X636641Y86254D02*
G02X635300Y85700I-1341J1346D01*
G01X636503Y84742D02*
G03X637490Y85405I-1196J2846D01*
G01X635300Y84500D02*
G03X636503Y84742I2J3101D01*
G01X641660Y91273D02*
X636641Y86254D01*
G01X637490Y85404D02*
X642584Y90498D01*
G01X635675Y112275D02*
X631008Y107608D01*
G01X629650Y107227D02*
G02X630159Y108457I1739J1D01*
G01X631008Y107608D02*
G03X630850Y107227I380J-381D01*
G01X629650Y106085D02*
Y107227D01*
G01X630850D02*
Y106086D01*
G01X630382Y104318D02*
G02X629650Y106085I1769J1768D01*
G01X630850Y106086D02*
G03X631231Y105167I1301J1D01*
G01X631268Y103432D02*
X630382Y104318D01*
G01X631231Y105167D02*
X632117Y104281D01*
G01X632000Y101664D02*
G03X631268Y103432I-2501J0D01*
G01X632117Y104281D02*
G02X633200Y101664I-2618J-2616D01*
G01X632000Y100734D02*
Y101664D01*
G01X633200D02*
Y100734D01*
G01X631268Y98966D02*
G03X632000Y100734I-1769J1768D01*
G01X633200D02*
G02X632117Y98117I-3701J-1D01*
G01X623100Y100236D02*
Y117763D01*
G01X624300Y100236D02*
Y117763D01*
G01X622719Y99317D02*
G03X623100Y100236I-920J920D01*
G01X623568Y98468D02*
G03X624300Y100236I-1769J1768D01*
G01X621287Y97884D02*
X622718Y99317D01*
G01X623567Y98467D02*
X623568Y98468D01*
G01X636768Y93668D02*
G03X637500Y95435I-1769J1768D01*
G01X634932Y91832D02*
X636768Y93668D01*
G01X635781Y90983D02*
X637617Y92819D01*
G01X633165Y91100D02*
G03X634932Y91833I-2J2501D01*
G01X633164Y89900D02*
G03X635781Y90983I1J3701D01*
G01X628537Y91100D02*
X633165D01*
G01X628929Y89900D02*
X633164D01*
G01X625800Y89100D02*
X628537Y91100D01*
G01X626719Y88285D02*
X628929Y89900D01*
G01X623751Y85449D02*
X625800Y89100D01*
G01X624717Y84717D02*
X626719Y88285D01*
G01X621227Y82926D02*
X623751Y85449D01*
G01X623850Y83850D02*
X624717Y84717D01*
G01X637490Y85404D02*
X642584Y90498D01*
G01X641660Y91273D02*
X636641Y86254D01*
G01X636503Y84742D02*
G03X637490Y85405I-1196J2846D01*
G01X636641Y86254D02*
G02X635300Y85700I-1341J1346D01*
G01Y84500D02*
G03X636503Y84742I2J3101D01*
G01X636641Y86254D02*
G02X635300Y85700I-1341J1346D01*
G01X634319Y84500D02*
X635300D01*
G01Y85700D02*
X634318D01*
G01X633357Y84281D02*
G02X634319Y84500I961J-2000D01*
G01X634318Y85700D02*
G03X632837Y85363I-1J-3419D01*
G01X632750Y83850D02*
G02X633357Y84281I1570J-1568D01*
G01X634318Y85700D02*
G03X632837Y85363I-1J-3419D01*
G01X631778Y82878D02*
X632750Y83850D01*
G01X631951Y84749D02*
X630887Y83684D01*
G01X633200Y100734D02*
G02X632117Y98117I-3701J-1D01*
G01X631268Y98966D02*
G03X632000Y100734I-1769J1768D01*
G01X633200Y101664D02*
Y100734D01*
G01X632000D02*
Y101664D01*
G01X632117Y104281D02*
G02X633200Y101664I-2618J-2616D01*
G01X632000D02*
G03X631268Y103432I-2501J0D01*
G01X631231Y105167D02*
X632117Y104281D01*
G01X631268Y103432D02*
X630382Y104318D01*
G01X630850Y106086D02*
G03X631231Y105167I1301J1D01*
G01X630382Y104318D02*
G02X629650Y106085I1769J1768D01*
G01X630850Y107227D02*
Y106086D01*
G01X629650Y106085D02*
Y107227D01*
G01X631008Y107608D02*
G03X630850Y107227I380J-381D01*
G01X629650D02*
G02X630159Y108457I1739J1D01*
G01X635675Y112275D02*
X631008Y107608D01*
G01X624300Y100236D02*
Y117763D01*
G01X623100Y100236D02*
Y117763D01*
G01X623568Y98468D02*
G03X624300Y100236I-1769J1768D01*
G01X622719Y99317D02*
G03X623100Y100236I-920J920D01*
G01X623567Y98467D02*
X623568Y98468D01*
G01X621287Y97884D02*
X622718Y99317D01*
G01X636768Y93668D02*
G03X637500Y95435I-1769J1768D01*
G01X635781Y90983D02*
X637617Y92819D01*
G01X634932Y91832D02*
X636768Y93668D01*
G01X633164Y89900D02*
G03X635781Y90983I1J3701D01*
G01X633165Y91100D02*
G03X634932Y91833I-2J2501D01*
G01X628929Y89900D02*
X633164D01*
G01X628537Y91100D02*
X633165D01*
G01X626719Y88285D02*
X628929Y89900D01*
G01X625800Y89100D02*
X628537Y91100D01*
G01X624717Y84717D02*
X626719Y88285D01*
G01X623751Y85449D02*
X625800Y89100D01*
G01X623850Y83850D02*
X624717Y84717D01*
G01X621227Y82926D02*
X623751Y85449D01*
G01X615419Y100578D02*
G02X614717Y98545I-3291J-1D01*
G01X614219Y100577D02*
G02X613773Y99286I-2091J0D01*
G01X615419Y101675D02*
Y100578D01*
G01X614219Y101675D02*
Y100577D01*
G01X615122Y103481D02*
G02X615419Y101675I-5338J-1805D01*
G01X613985Y103097D02*
G02X614219Y101675I-4201J-1422D01*
G01X614971Y103855D02*
G02X615122Y103481I-3053J-1450D01*
G01X613461Y103941D02*
G02X613985Y103097I-1541J-1542D01*
G01X614308Y104793D02*
G02X614971Y103855I-2395J-2396D01*
G01X613461Y103941D02*
G02X613985Y103097I-1541J-1542D01*
G01X613850Y105251D02*
X614308Y104793D01*
G01X612951Y104452D02*
X613451Y103952D01*
G01X613350Y106020D02*
G03X613850Y105251I2068J797D01*
G01X612001Y106817D02*
G03X612230Y105587I3416J0D01*
G01X613201Y106818D02*
G03X613350Y106020I2216J1D01*
G01X612001Y106817D02*
G03X612230Y105587I3416J0D01*
G01X613201Y114044D02*
Y106818D01*
G01X612001Y114044D02*
Y106817D01*
G01X614219Y100577D02*
G02X613773Y99286I-2091J0D01*
G01X615419Y100578D02*
G02X614717Y98545I-3291J-1D01*
G01X614219Y101675D02*
Y100577D01*
G01X615419Y101675D02*
Y100578D01*
G01X613985Y103097D02*
G02X614219Y101675I-4201J-1422D01*
G01X615122Y103481D02*
G02X615419Y101675I-5338J-1805D01*
G01X613461Y103941D02*
G02X613985Y103097I-1541J-1542D01*
G01X614971Y103855D02*
G02X615122Y103481I-3053J-1450D01*
G01X614308Y104793D02*
G02X614971Y103855I-2395J-2396D01*
G01X612951Y104452D02*
X613451Y103952D01*
G01X613850Y105251D02*
X614308Y104793D01*
G01X612001Y106817D02*
G03X612230Y105587I3416J0D01*
G01X613350Y106020D02*
G03X613850Y105251I2068J797D01*
G01X613201Y106818D02*
G03X613350Y106020I2216J1D01*
G01X612001Y114044D02*
Y106817D01*
G01X613201Y114044D02*
Y106818D01*
G01X635820Y135560D02*
Y136240D01*
G01X637020Y135560D02*
Y136240D01*
G01X625496Y135560D02*
Y136240D01*
G01X626696Y135560D02*
Y136240D01*
G01X637020Y135560D02*
Y136240D01*
G01X635820Y135560D02*
Y136240D01*
G01X626696Y135560D02*
Y136240D01*
G01X625496Y135560D02*
Y136240D01*
G01X635820Y135560D02*
Y136240D01*
G01X637020Y135560D02*
Y136240D01*
G01X625496Y135560D02*
Y136240D01*
G01X626696Y135560D02*
Y136240D01*
G01X637020Y135560D02*
Y136240D01*
G01X635820Y135560D02*
Y136240D01*
G01X626696Y135560D02*
Y136240D01*
G01X625496Y135560D02*
Y136240D01*
G01X635650Y115112D02*
Y128600D01*
G01X636850D02*
Y115113D01*
G01X634826Y113124D02*
G03X635649Y115113I-1987J1987D01*
G01X636850D02*
G02X635675Y112275I-4010J-2D01*
G01X630159Y108457D02*
X634826Y113124D01*
G01X625326Y120996D02*
Y128600D01*
G01X626526Y120997D02*
Y128600D01*
G01X625168Y120616D02*
G03X625325Y120997I-381J380D01*
G01X626017Y119767D02*
G03X626526Y120997I-1230J1229D01*
G01X623654Y119102D02*
X625168Y120616D01*
G01X624503Y118253D02*
X626017Y119767D01*
G01X623100Y117763D02*
G02X623654Y119102I1893J1D01*
G01X624300Y117763D02*
G02X624503Y118253I693J0D01*
G01X630159Y108457D02*
X634826Y113124D01*
G01X636850Y115113D02*
G02X635675Y112275I-4010J-2D01*
G01X634826Y113124D02*
G03X635649Y115113I-1987J1987D01*
G01X636850Y128600D02*
Y115113D01*
G01X635650Y115112D02*
Y128600D01*
G01X626526Y120997D02*
Y128600D01*
G01X625326Y120996D02*
Y128600D01*
G01X626017Y119767D02*
G03X626526Y120997I-1230J1229D01*
G01X625168Y120616D02*
G03X625325Y120997I-381J380D01*
G01X624503Y118253D02*
X626017Y119767D01*
G01X623654Y119102D02*
X625168Y120616D01*
G01X624300Y117763D02*
G02X624503Y118253I693J0D01*
G01X623100Y117763D02*
G02X623654Y119102I1893J1D01*
G01X613851Y115613D02*
G03X613201Y114044I1569J-1569D01*
G01X613002Y116462D02*
G03X612001Y114044I2418J-2417D01*
G01X615707Y117469D02*
X613851Y115613D01*
G01X614858Y118318D02*
X613002Y116462D01*
G01X616217Y118699D02*
G02X615707Y117469I-1740J1D01*
G01X615017Y118700D02*
G02X614858Y118318I-540J0D01*
G01X616217Y128337D02*
Y118699D01*
G01X615017Y128523D02*
Y118700D01*
G01X613002Y116462D02*
G03X612001Y114044I2418J-2417D01*
G01X613851Y115613D02*
G03X613201Y114044I1569J-1569D01*
G01X614858Y118318D02*
X613002Y116462D01*
G01X615707Y117469D02*
X613851Y115613D01*
G01X615017Y118700D02*
G02X614858Y118318I-540J0D01*
G01X616217Y118699D02*
G02X615707Y117469I-1740J1D01*
G01X615017Y128523D02*
Y118700D01*
G01X616217Y128337D02*
Y118699D01*
G01X637400Y328852D02*
X641600Y324652D01*
G01X637400Y328852D02*
X641600Y324652D01*
G01X637400Y328852D02*
X641600Y324652D01*
G01X637046Y339953D02*
G02X637400Y339100I-853J-854D01*
G01X637000Y340000D02*
X637046Y339953D01*
G01X635523Y343175D02*
X637892Y340806D01*
G01X634323Y342677D02*
X637000Y340000D01*
G01X635523Y343175D02*
X637892Y340806D01*
G01X634323Y344561D02*
Y342677D01*
G01X635523Y344534D02*
Y343175D01*
G01X637400Y328852D02*
X641600Y324652D01*
G01X637046Y339953D02*
G02X637400Y339100I-853J-854D01*
G01X635523Y343175D02*
X637892Y340806D01*
G01X637000Y340000D02*
X637046Y339953D01*
G01X634323Y342677D02*
X637000Y340000D01*
G01X635523Y344534D02*
Y343175D01*
G01X634323Y344561D02*
Y342677D01*
G01X635865Y370066D02*
X637742Y371943D01*
G01X637245Y373144D02*
X635000Y370899D01*
G01X635600Y369426D02*
G02X635865Y370066I905J0D01*
G01X635000Y370899D02*
G03X634400Y369450I1449J-1449D01*
G01X635600Y368550D02*
Y369426D01*
G01X634400Y369450D02*
Y368494D01*
G01Y369450D02*
Y368494D01*
G01X635600Y368550D02*
Y369426D01*
G01X635000Y370899D02*
G03X634400Y369450I1449J-1449D01*
G01X635600Y369426D02*
G02X635865Y370066I905J0D01*
G01X637245Y373144D02*
X635000Y370899D01*
G01X635865Y370066D02*
X637742Y371943D01*
G01X609218Y832800D02*
Y831800D01*
G01X610418Y832800D02*
Y831700D01*
G01X621817Y832800D02*
Y831700D01*
G01X623017Y832800D02*
Y831700D01*
G01X634415Y832800D02*
Y831800D01*
G01X635615Y832800D02*
Y831800D01*
G01X610418Y832800D02*
Y831700D01*
G01X609218Y832800D02*
Y831800D01*
G01X623017Y832800D02*
Y831700D01*
G01X621817Y832800D02*
Y831700D01*
G01X635615Y832800D02*
Y831800D01*
G01X634415Y832800D02*
Y831800D01*
G01X609243Y882407D02*
Y841431D01*
G01X610444Y882416D02*
Y841428D01*
G01X621842Y882407D02*
Y841431D01*
G01X623043Y882416D02*
Y841428D01*
G01X634440Y882407D02*
Y841431D01*
G01X635641Y882416D02*
Y841428D01*
G01X610444Y882416D02*
Y841428D01*
G01X609243Y882407D02*
Y841431D01*
G01X623043Y882416D02*
Y841428D01*
G01X621842Y882407D02*
Y841431D01*
G01X635641Y882416D02*
Y841428D01*
G01X634440Y882407D02*
Y841431D01*
G01X609218Y832800D02*
Y831800D01*
G01X610418Y832800D02*
Y831700D01*
G01X621817Y832800D02*
Y831700D01*
G01X623017Y832800D02*
Y831700D01*
G01X634415Y832800D02*
Y831800D01*
G01X635615Y832800D02*
Y831800D01*
G01X610418Y832800D02*
Y831700D01*
G01X609218Y832800D02*
Y831800D01*
G01X623017Y832800D02*
Y831700D01*
G01X621817Y832800D02*
Y831700D01*
G01X635615Y832800D02*
Y831800D01*
G01X634415Y832800D02*
Y831800D01*
G01X657250Y54551D02*
X657153Y54454D01*
G01X659049Y54651D02*
X658099Y53701D01*
G01X658200Y55500D02*
X657250Y54550D01*
G01X659049Y54651D02*
X658099Y53701D01*
G01X658999Y57430D02*
G02X658200Y55500I-2729J0D01*
G01X660200Y57430D02*
G02X659049Y54651I-3930J0D01*
G01X659000Y57968D02*
Y57429D01*
G01X660200Y57968D02*
Y57430D01*
G01X661232Y60200D02*
G03X659000Y57968I0J-2232D01*
G01X661232Y59000D02*
G03X660200Y57968I0J-1032D01*
G01X665211Y60200D02*
X661232D01*
G01X665213Y59000D02*
X661232D01*
G01X665854Y60144D02*
G03X665211Y60200I-641J-3644D01*
G01X665646Y58962D02*
G03X665213Y59000I-434J-2462D01*
G01X675522Y58440D02*
X665854Y60144D01*
G01X675417Y57240D02*
X665646Y58962D01*
G01X659049Y54651D02*
X658099Y53701D01*
G01X657250Y54551D02*
X657153Y54454D01*
G01X658200Y55500D02*
X657250Y54550D01*
G01X660200Y57430D02*
G02X659049Y54651I-3930J0D01*
G01X658999Y57430D02*
G02X658200Y55500I-2729J0D01*
G01X660200Y57968D02*
Y57430D01*
G01X659000Y57968D02*
Y57429D01*
G01X661232Y59000D02*
G03X660200Y57968I0J-1032D01*
G01X661232Y60200D02*
G03X659000Y57968I0J-2232D01*
G01X665213Y59000D02*
X661232D01*
G01X665211Y60200D02*
X661232D01*
G01X665646Y58962D02*
G03X665213Y59000I-434J-2462D01*
G01X665854Y60144D02*
G03X665211Y60200I-641J-3644D01*
G01X675417Y57240D02*
X665646Y58962D01*
G01X675522Y58440D02*
X665854Y60144D01*
G01X674778Y112632D02*
X671191Y107510D01*
G01X669881Y107408D02*
G02X670207Y108198I1945J-340D01*
G01X671191Y107510D02*
G03X671063Y107200I635J-444D01*
G01X669679Y106261D02*
X669881Y107408D01*
G01X671063Y107200D02*
X670861Y106053D01*
G01X669247Y104809D02*
G03X669679Y106261I-6118J2611D01*
G01X670861Y106053D02*
G02X670352Y104338I-7734J1362D01*
G01X668724Y103582D02*
X669247Y104809D01*
G01X670352Y104338D02*
X669829Y103111D01*
G01X668182Y102780D02*
G03X668724Y103582I-1791J1795D01*
G01X669829Y103111D02*
G02X669030Y101930I-3437J1465D01*
G01X668181Y102780D02*
X668182D01*
G01X669030Y101930D02*
X668509Y101410D01*
G01X667661Y102260D02*
X668181Y102780D01*
G01X669030Y101930D02*
X668509Y101410D01*
G01X665816Y99740D02*
G02X667661Y102260I9012J-4663D01*
G01X666882Y99188D02*
G03X666460Y98242I7934J-4106D01*
G01X668509Y101410D02*
G03X666882Y99188I6319J-6334D01*
G01X665506Y99084D02*
G02X665816Y99740I9310J-3998D01*
G01X666882Y99188D02*
G03X666460Y98242I7934J-4106D01*
G01X668509Y101410D02*
G03X666882Y99188I6319J-6334D01*
G01X669800Y90100D02*
X672300Y91100D01*
G01X670511Y89091D02*
X672460Y89871D01*
G01X668300Y88400D02*
X669800Y90100D01*
G01X669340Y87763D02*
X670511Y89091D01*
G01X667195Y85604D02*
X668300Y88400D01*
G01X668220Y84931D02*
X669340Y87763D01*
G01X665795Y84204D02*
X667195Y85604D01*
G01X666944Y83655D02*
X668220Y84931D01*
G01X666882Y99188D02*
G03X666460Y98242I7934J-4106D01*
G01X665816Y99740D02*
G02X667661Y102260I9012J-4663D01*
G01X665506Y99084D02*
G02X665816Y99740I9310J-3998D01*
G01X668509Y101410D02*
G03X666882Y99188I6319J-6334D01*
G01X665816Y99740D02*
G02X667661Y102260I9012J-4663D01*
G01X665506Y99084D02*
G02X665816Y99740I9310J-3998D01*
G01X669030Y101930D02*
X668509Y101410D01*
G01X668181Y102780D02*
X668182D01*
G01X667661Y102260D02*
X668181Y102780D01*
G01X669829Y103111D02*
G02X669030Y101930I-3437J1465D01*
G01X668182Y102780D02*
G03X668724Y103582I-1791J1795D01*
G01X670352Y104338D02*
X669829Y103111D01*
G01X668724Y103582D02*
X669247Y104809D01*
G01X670861Y106053D02*
G02X670352Y104338I-7734J1362D01*
G01X669247Y104809D02*
G03X669679Y106261I-6118J2611D01*
G01X671063Y107200D02*
X670861Y106053D01*
G01X669679Y106261D02*
X669881Y107408D01*
G01X671191Y107510D02*
G03X671063Y107200I635J-444D01*
G01X669881Y107408D02*
G02X670207Y108198I1945J-340D01*
G01X674778Y112632D02*
X671191Y107510D01*
G01X670511Y89091D02*
X672460Y89871D01*
G01X669800Y90100D02*
X672300Y91100D01*
G01X669340Y87763D02*
X670511Y89091D01*
G01X668300Y88400D02*
X669800Y90100D01*
G01X668220Y84931D02*
X669340Y87763D01*
G01X667195Y85604D02*
X668300Y88400D01*
G01X666944Y83655D02*
X668220Y84931D01*
G01X665795Y84204D02*
X667195Y85604D01*
G01X658951Y99550D02*
X658196Y98795D01*
G01X657451Y99749D02*
X656856Y99153D01*
G01X658101Y100399D02*
X657451Y99749D01*
G01X659029Y99629D02*
X658951Y99550D01*
G01X658101Y100399D02*
X657451Y99749D01*
G01X659092Y99721D02*
X659029Y99629D01*
G01X659511Y102463D02*
X658101Y100399D01*
G01X660379Y101604D02*
X659092Y99722D01*
G01X659511Y102463D02*
X658101Y100399D01*
G01X662457Y103056D02*
X660379Y101604D01*
G01X661682Y103980D02*
X659511Y102463D01*
G01X663449Y104049D02*
X662457Y103056D01*
G01X662526Y104823D02*
X661682Y103980D01*
G01X665219Y106576D02*
X663449Y104049D01*
G01X664236Y107265D02*
X662526Y104823D01*
G01X665996Y108452D02*
G02X665219Y106576I-4611J811D01*
G01X664814Y108660D02*
G02X664236Y107265I-3429J603D01*
G01X657451Y99749D02*
X656856Y99153D01*
G01X658951Y99550D02*
X658196Y98795D01*
G01X658101Y100399D02*
X657451Y99749D01*
G01X658951Y99550D02*
X658196Y98795D01*
G01X659029Y99629D02*
X658951Y99550D01*
G01X659511Y102463D02*
X658101Y100399D01*
G01X659092Y99721D02*
X659029Y99629D01*
G01X660379Y101604D02*
X659092Y99722D01*
G01X661682Y103980D02*
X659511Y102463D01*
G01X662457Y103056D02*
X660379Y101604D01*
G01X662526Y104823D02*
X661682Y103980D01*
G01X663449Y104049D02*
X662457Y103056D01*
G01X664236Y107265D02*
X662526Y104823D01*
G01X665219Y106576D02*
X663449Y104049D01*
G01X664814Y108660D02*
G02X664236Y107265I-3429J603D01*
G01X665996Y108452D02*
G02X665219Y106576I-4611J811D01*
G01X660063Y117579D02*
X641660Y91273D01*
G01X642584Y90498D02*
X660926Y116717D01*
G01X643650Y106782D02*
Y128600D01*
G01X644850Y106783D02*
Y128600D01*
G01X642917Y105015D02*
G03X643649Y106783I-1767J1767D01*
G01X643766Y104166D02*
G03X644850Y106783I-2616J2617D01*
G01X638358Y100456D02*
X642917Y105015D01*
G01X639207Y99607D02*
X643766Y104166D01*
G01X637500Y98383D02*
G02X638358Y100456I2931J1D01*
G01X638700Y98383D02*
G02X639207Y99607I1731J0D01*
G01X637500Y95435D02*
Y98383D01*
G01X638700Y95434D02*
Y98383D01*
G01X637617Y92819D02*
G03X638700Y95434I-2618J2616D01*
G01X642584Y90498D02*
X660926Y116717D01*
G01X660063Y117579D02*
X641660Y91273D01*
G01X644850Y106783D02*
Y128600D01*
G01X643650Y106782D02*
Y128600D01*
G01X643766Y104166D02*
G03X644850Y106783I-2616J2617D01*
G01X642917Y105015D02*
G03X643649Y106783I-1767J1767D01*
G01X639207Y99607D02*
X643766Y104166D01*
G01X638358Y100456D02*
X642917Y105015D01*
G01X638700Y98383D02*
G02X639207Y99607I1731J0D01*
G01X637500Y98383D02*
G02X638358Y100456I2931J1D01*
G01X638700Y95434D02*
Y98383D01*
G01X637500Y95435D02*
Y98383D01*
G01X637617Y92819D02*
G03X638700Y95434I-2618J2616D01*
G01X643650Y138256D02*
Y135600D01*
G01X644850Y138256D02*
Y135600D01*
G01X642945Y139957D02*
G02X643650Y138256I-1702J-1702D01*
G01X643794Y140806D02*
G02X644850Y138256I-2551J-2550D01*
G01X639714Y143188D02*
X642945Y139957D01*
G01X640563Y144037D02*
X643794Y140806D01*
G01X644850Y138256D02*
Y135600D01*
G01X643650Y138256D02*
Y135600D01*
G01X643794Y140806D02*
G02X644850Y138256I-2551J-2550D01*
G01X642945Y139957D02*
G02X643650Y138256I-1702J-1702D01*
G01X640563Y144037D02*
X643794Y140806D01*
G01X639714Y143188D02*
X642945Y139957D01*
G01X644850Y138256D02*
Y135600D01*
G01X643650Y138256D02*
Y135600D01*
G01X643794Y140806D02*
G02X644850Y138256I-2551J-2550D01*
G01X642945Y139957D02*
G02X643650Y138256I-1702J-1702D01*
G01X640563Y144037D02*
X643794Y140806D01*
G01X639714Y143188D02*
X642945Y139957D01*
G01X670207Y108198D02*
X673794Y113321D01*
G01X670207Y108198D02*
X673794Y113321D01*
G01X666163Y109402D02*
X665996Y108452D01*
G01X664981Y109610D02*
X664814Y108660D01*
G01X666550Y110337D02*
G03X666163Y109402I1912J-1339D01*
G01X665566Y111026D02*
G03X664981Y109610I2897J-2026D01*
G01X670033Y115310D02*
X666550Y110337D01*
G01X669049Y115999D02*
X665566Y111026D01*
G01X671624Y116901D02*
G03X670033Y115310I3719J-5310D01*
G01X670935Y117885D02*
G03X669049Y115999I4407J-6293D01*
G01X674329Y120261D02*
X670935Y117885D01*
G01X664981Y109610D02*
X664814Y108660D01*
G01X666163Y109402D02*
X665996Y108452D01*
G01X665566Y111026D02*
G03X664981Y109610I2897J-2026D01*
G01X666550Y110337D02*
G03X666163Y109402I1912J-1339D01*
G01X669049Y115999D02*
X665566Y111026D01*
G01X670033Y115310D02*
X666550Y110337D01*
G01X670935Y117885D02*
G03X669049Y115999I4407J-6293D01*
G01X671624Y116901D02*
G03X670033Y115310I3719J-5310D01*
G01X674329Y120261D02*
X670935Y117885D01*
G01X643650Y138256D02*
Y135600D01*
G01X644850Y138256D02*
Y135600D01*
G01X642945Y139957D02*
G02X643650Y138256I-1702J-1702D01*
G01X643794Y140806D02*
G02X644850Y138256I-2551J-2550D01*
G01X639714Y143188D02*
X642945Y139957D01*
G01X640563Y144037D02*
X643794Y140806D01*
G01X670292Y124742D02*
X660063Y117579D01*
G01X660926Y116717D02*
X670981Y123758D01*
G01X672080Y125481D02*
G03X670292Y124742I772J-4400D01*
G01X670981Y123758D02*
G02X672288Y124299I1873J-2677D01*
G01X670981Y123758D02*
G02X672288Y124299I1873J-2677D01*
G01X672080Y125481D02*
G03X670292Y124742I772J-4400D01*
G01X660926Y116717D02*
X670981Y123758D01*
G01X670292Y124742D02*
X660063Y117579D01*
G01X638090Y147110D02*
G03X639714Y143188I5546J-1D01*
G01X639290Y147110D02*
G03X640563Y144037I4346J0D01*
G01X639290Y147110D02*
G03X640563Y144037I4346J0D01*
G01X638090Y147110D02*
G03X639714Y143188I5546J-1D01*
G01X639290Y147110D02*
G03X640563Y144037I4346J0D01*
G01X638090Y147110D02*
G03X639714Y143188I5546J-1D01*
G01X638090Y147110D02*
G03X639714Y143188I5546J-1D01*
G01X639290Y147110D02*
G03X640563Y144037I4346J0D01*
G01X641600Y324652D02*
Y323299D01*
G01X642800Y325150D02*
Y323300D01*
G01X638600Y329350D02*
X642800Y325150D01*
G01X637400Y331400D02*
Y328852D01*
G01X638600Y331400D02*
Y329350D01*
G01X642800Y325150D02*
Y323300D01*
G01X641600Y324652D02*
Y323299D01*
G01X638600Y329350D02*
X642800Y325150D01*
G01X638600Y331400D02*
Y329350D01*
G01X637400Y331400D02*
Y328852D01*
G01X642800Y325150D02*
Y323300D01*
G01X641600Y324652D02*
Y323299D01*
G01X638600Y329350D02*
X642800Y325150D01*
G01X638600Y331400D02*
Y329350D01*
G01X637400Y331400D02*
Y328852D01*
G01X637892Y340806D02*
G02X638599Y339099I-1707J-1707D01*
G01X641600Y324652D02*
Y323299D01*
G01X642800Y325150D02*
Y323300D01*
G01X638600Y329350D02*
X642800Y325150D01*
G01X637400Y331400D02*
Y328852D01*
G01X638600Y331400D02*
Y329350D01*
G01X637892Y340806D02*
G02X638599Y339099I-1707J-1707D01*
G01X657180Y350030D02*
X659214D01*
G01X657120Y351230D02*
X659274D01*
G01X657120D02*
X659274D01*
G01X657180Y350030D02*
X659214D01*
G01X649212Y364000D02*
X649936D01*
G01X649212Y365200D02*
X649900D01*
G01X648505Y363707D02*
G02X649212Y364000I707J-706D01*
G01X647656Y364556D02*
G02X649212Y365200I1555J-1556D01*
G01X648100Y362810D02*
G02X648449Y363651I1190J-1D01*
G01X646900Y362811D02*
G02X647600Y364500I2390J-1D01*
G01X647292Y360793D02*
G03X648100Y362748I-1957J1953D01*
G01X646442Y361642D02*
G03X646900Y362748I-1106J1106D01*
G01X645336Y361183D02*
G03X646443Y361642I0J1565D01*
G01X645335Y359983D02*
G03X647292Y360793I2J2765D01*
G01X646442Y361642D02*
G03X646900Y362748I-1106J1106D01*
G01X645336Y361183D02*
G03X646443Y361642I0J1565D01*
G01X644987Y359983D02*
X645335D01*
G01X644987Y361183D02*
X645336D01*
G01X644468Y359768D02*
G02X644987Y359983I519J-519D01*
G01X644856Y361179D02*
G02X644987Y361183I125J-1931D01*
G01X649400Y350000D02*
X650100D01*
G01X649400Y351200D02*
X650249D01*
G01X647863Y350636D02*
G03X649400Y350000I1536J1537D01*
G01X648713Y351484D02*
G03X649400Y351200I686J687D01*
G01X646700Y351800D02*
X647850Y350650D01*
G01X648599Y351599D02*
X648713Y351484D01*
G01X647549Y352649D02*
X648599Y351599D01*
G01X645976Y352100D02*
G02X646700Y351800I0J-1024D01*
G01X645977Y353300D02*
G02X647549Y352649I0J-2224D01*
G01X645098Y352100D02*
X645976D01*
G01X644945Y353300D02*
X645977D01*
G01X649212Y365200D02*
X649900D01*
G01X649212Y364000D02*
X649936D01*
G01X647656Y364556D02*
G02X649212Y365200I1555J-1556D01*
G01X648505Y363707D02*
G02X649212Y364000I707J-706D01*
G01X646900Y362811D02*
G02X647600Y364500I2390J-1D01*
G01X648100Y362810D02*
G02X648449Y363651I1190J-1D01*
G01X646442Y361642D02*
G03X646900Y362748I-1106J1106D01*
G01X647292Y360793D02*
G03X648100Y362748I-1957J1953D01*
G01X645335Y359983D02*
G03X647292Y360793I2J2765D01*
G01X645336Y361183D02*
G03X646443Y361642I0J1565D01*
G01X647292Y360793D02*
G03X648100Y362748I-1957J1953D01*
G01X645335Y359983D02*
G03X647292Y360793I2J2765D01*
G01X644987Y361183D02*
X645336D01*
G01X644987Y359983D02*
X645335D01*
G01X644856Y361179D02*
G02X644987Y361183I125J-1931D01*
G01X644468Y359768D02*
G02X644987Y359983I519J-519D01*
G01X649400Y351200D02*
X650249D01*
G01X649400Y350000D02*
X650100D01*
G01X648713Y351484D02*
G03X649400Y351200I686J687D01*
G01X647863Y350636D02*
G03X649400Y350000I1536J1537D01*
G01X648599Y351599D02*
X648713Y351484D01*
G01X646700Y351800D02*
X647850Y350650D01*
G01X647549Y352649D02*
X648599Y351599D01*
G01X646700Y351800D02*
X647850Y350650D01*
G01X645977Y353300D02*
G02X647549Y352649I0J-2224D01*
G01X645976Y352100D02*
G02X646700Y351800I0J-1024D01*
G01X644945Y353300D02*
X645977D01*
G01X645098Y352100D02*
X645976D01*
G01X657120Y351230D02*
X659274D01*
G01X657180Y350030D02*
X659214D01*
G01X657180D02*
X659214D01*
G01X657120Y351230D02*
X659274D01*
G01X656462Y832800D02*
Y831850D01*
G01X657662Y832800D02*
Y831850D01*
G01X669060Y831845D02*
G02X668658Y830873I-1374J-1D01*
G01X670260Y831846D02*
G02Y831830I-2575J-8D01*
G01X669060Y832800D02*
Y831845D01*
G01X670260Y832800D02*
Y831846D01*
G01X657662Y832800D02*
Y831850D01*
G01X656462Y832800D02*
Y831850D01*
G01X670260Y831846D02*
G02Y831830I-2575J-8D01*
G01X669060Y831845D02*
G02X668658Y830873I-1374J-1D01*
G01X670260Y832800D02*
Y831846D01*
G01X669060Y832800D02*
Y831845D01*
G01X656487Y882407D02*
Y841431D01*
G01X657688Y882416D02*
Y841428D01*
G01X669085Y882407D02*
Y841431D01*
G01X670286Y882416D02*
Y841428D01*
G01X657688Y882416D02*
Y841428D01*
G01X656487Y882407D02*
Y841431D01*
G01X670286Y882416D02*
Y841428D01*
G01X669085Y882407D02*
Y841431D01*
G01X656462Y832800D02*
Y831850D01*
G01X657662Y832800D02*
Y831850D01*
G01X669060Y831845D02*
G02X668658Y830873I-1374J-1D01*
G01X670260Y831846D02*
G02Y831830I-2575J-8D01*
G01X669060Y832800D02*
Y831845D01*
G01X670260Y832800D02*
Y831846D01*
G01X657662Y832800D02*
Y831850D01*
G01X656462Y832800D02*
Y831850D01*
G01X670260Y831846D02*
G02Y831830I-2575J-8D01*
G01X669060Y831845D02*
G02X668658Y830873I-1374J-1D01*
G01X670260Y832800D02*
Y831846D01*
G01X669060Y832800D02*
Y831845D01*
G01X691466Y58440D02*
X675522D01*
G01X691466Y57240D02*
X675417D01*
G01X696269Y56451D02*
G03X691466Y58440I-4802J-4803D01*
G01X695420Y55602D02*
G03X691466Y57240I-3954J-3953D01*
G01X697535Y55185D02*
X696269Y56451D01*
G01X696686Y54336D02*
X695420Y55602D01*
G01X699020Y54570D02*
G02X697535Y55185I0J2101D01*
G01X699021Y53369D02*
G02X696686Y54336I0J3301D01*
G01X712070Y54570D02*
X699020D01*
G01X699898Y53370D02*
X699021Y53369D01*
G01X711786Y53370D02*
X699898D01*
G01X691466Y57240D02*
X675417D01*
G01X691466Y58440D02*
X675522D01*
G01X695420Y55602D02*
G03X691466Y57240I-3954J-3953D01*
G01X696269Y56451D02*
G03X691466Y58440I-4802J-4803D01*
G01X696686Y54336D02*
X695420Y55602D01*
G01X697535Y55185D02*
X696269Y56451D01*
G01X699021Y53369D02*
G02X696686Y54336I0J3301D01*
G01X699020Y54570D02*
G02X697535Y55185I0J2101D01*
G01X699898Y53370D02*
X699021Y53369D01*
G01X712070Y54570D02*
X699020D01*
G01X711786Y53370D02*
X699898D01*
G01X712070Y54570D02*
X699020D01*
G01X683139Y80350D02*
X710474D01*
G01X683139Y79150D02*
X710474D01*
G01X682299Y80699D02*
G03X683139Y80350I841J838D01*
G01X681450Y79850D02*
G03X683139Y79150I1689J1688D01*
G01X680751Y81500D02*
G03X681423Y79877I2296J0D01*
G01X681951Y81500D02*
G03X682272Y80726I1096J1D01*
G01X681450Y79850D02*
G03X683139Y79150I1689J1688D01*
G01X680751Y81500D02*
G03X681423Y79877I2296J0D01*
G01X680928Y83972D02*
G02X681951Y81500I-2473J-2471D01*
G01X680751D02*
G03X681423Y79877I2296J0D01*
G01X680079Y83123D02*
G02X680751Y81500I-1624J-1623D01*
G01X680250Y84650D02*
X680928Y83972D01*
G01X679401Y83801D02*
X680079Y83123D01*
G01X679091Y85404D02*
G02X680250Y84650I-1200J-3113D01*
G01X678659Y84283D02*
G02X679401Y83801I-768J-1994D01*
G01X677890Y84426D02*
G02X678659Y84283I0J-2137D01*
G01X677891Y85627D02*
G02X679091Y85404I1J-3336D01*
G01X678659Y84283D02*
G02X679401Y83801I-768J-1994D01*
G01X677890Y84426D02*
G02X678659Y84283I0J-2137D01*
G01X677497Y85627D02*
X677891D01*
G01X677496Y84427D02*
X677890D01*
G01X676027Y85297D02*
G02X677497Y85627I1467J-3094D01*
G01X676542Y84211D02*
G02X677496Y84427I956J-2007D01*
G01X675924Y83776D02*
G02X676542Y84211I1570J-1574D01*
G01X675350Y99757D02*
G03X675246Y99657I2320J-2517D01*
G01X676859Y99307D02*
G03X676164Y98875I806J-2071D01*
G01X676424Y100426D02*
G03X675350Y99757I1241J-3189D01*
G01X676859Y99307D02*
G03X676164Y98875I806J-2071D01*
G01X677877Y100668D02*
G03X676424Y100426I-149J-3591D01*
G01X677827Y99468D02*
G03X676859Y99307I-100J-2391D01*
G01X680266Y99620D02*
G03X677877Y100668I-2538J-2538D01*
G01X677827Y99468D02*
G03X676859Y99307I-100J-2391D01*
G01X679419Y98769D02*
G03X677827Y99468I-1692J-1692D01*
G01X683936Y95950D02*
X680266Y99620D01*
G01X683086Y95102D02*
X679419Y98769D01*
G01X685704Y95218D02*
G02X683936Y95950I0J2500D01*
G01X685703Y94018D02*
G02X683086Y95102I0J3700D01*
G01X711200Y95218D02*
X685704D01*
G01X711200Y94018D02*
X685703D01*
G01X683139Y79150D02*
X710474D01*
G01X683139Y80350D02*
X710474D01*
G01X681450Y79850D02*
G03X683139Y79150I1689J1688D01*
G01X682299Y80699D02*
G03X683139Y80350I841J838D01*
G01X681951Y81500D02*
G03X682272Y80726I1096J1D01*
G01X680751Y81500D02*
G03X681423Y79877I2296J0D01*
G01X682299Y80699D02*
G03X683139Y80350I841J838D01*
G01X681951Y81500D02*
G03X682272Y80726I1096J1D01*
G01X680928Y83972D02*
G02X681951Y81500I-2473J-2471D01*
G01X680079Y83123D02*
G02X680751Y81500I-1624J-1623D01*
G01X680928Y83972D02*
G02X681951Y81500I-2473J-2471D01*
G01X679401Y83801D02*
X680079Y83123D01*
G01X680250Y84650D02*
X680928Y83972D01*
G01X678659Y84283D02*
G02X679401Y83801I-768J-1994D01*
G01X679091Y85404D02*
G02X680250Y84650I-1200J-3113D01*
G01X677891Y85627D02*
G02X679091Y85404I1J-3336D01*
G01X677890Y84426D02*
G02X678659Y84283I0J-2137D01*
G01X679091Y85404D02*
G02X680250Y84650I-1200J-3113D01*
G01X677891Y85627D02*
G02X679091Y85404I1J-3336D01*
G01X677496Y84427D02*
X677890D01*
G01X677497Y85627D02*
X677891D01*
G01X676542Y84211D02*
G02X677496Y84427I956J-2007D01*
G01X676027Y85297D02*
G02X677497Y85627I1467J-3094D01*
G01X675924Y83776D02*
G02X676542Y84211I1570J-1574D01*
G01X676027Y85297D02*
G02X677497Y85627I1467J-3094D01*
G01X676859Y99307D02*
G03X676164Y98875I806J-2071D01*
G01X675350Y99757D02*
G03X675246Y99657I2320J-2517D01*
G01X676424Y100426D02*
G03X675350Y99757I1241J-3189D01*
G01X677827Y99468D02*
G03X676859Y99307I-100J-2391D01*
G01X677877Y100668D02*
G03X676424Y100426I-149J-3591D01*
G01X680266Y99620D02*
G03X677877Y100668I-2538J-2538D01*
G01X679419Y98769D02*
G03X677827Y99468I-1692J-1692D01*
G01X680266Y99620D02*
G03X677877Y100668I-2538J-2538D01*
G01X683086Y95102D02*
X679419Y98769D01*
G01X683936Y95950D02*
X680266Y99620D01*
G01X685703Y94018D02*
G02X683086Y95102I0J3700D01*
G01X685704Y95218D02*
G02X683936Y95950I0J2500D01*
G01X711200Y94018D02*
X685703D01*
G01X711200Y95218D02*
X685704D01*
G01X702491Y105651D02*
G03X707700Y104350I5209J9779D01*
G01Y103150D02*
G02X701861Y104627I0J12280D01*
G01X688824Y115219D02*
X702491Y105651D01*
G01X701861Y104627D02*
X688135Y114235D01*
G01X703425Y90465D02*
G02X705999Y89399I0J-3641D01*
G01X703424Y89265D02*
G02X705150Y88550I0J-2441D01*
G01X677500Y90465D02*
X703425D01*
G01X677427Y89265D02*
X703424D01*
G01X672300Y91100D02*
X677500Y90465D01*
G01X672460Y89871D02*
X677427Y89265D01*
G01X701861Y104627D02*
X688135Y114235D01*
G01X688824Y115219D02*
X702491Y105651D01*
G01X707700Y103150D02*
G02X701861Y104627I0J12280D01*
G01X702491Y105651D02*
G03X707700Y104350I5209J9779D01*
G01X703424Y89265D02*
G02X705150Y88550I0J-2441D01*
G01X703425Y90465D02*
G02X705999Y89399I0J-3641D01*
G01X677427Y89265D02*
X703424D01*
G01X677500Y90465D02*
X703425D01*
G01X672460Y89871D02*
X677427Y89265D01*
G01X672300Y91100D02*
X677500Y90465D01*
G01X686890Y116111D02*
G02X688824Y115219I-1508J-5812D01*
G01X688135Y114235D02*
G03X686588Y114949I-2754J-3935D01*
G01X685189Y116553D02*
X686890Y116111D01*
G01X686588Y114949D02*
X684887Y115391D01*
G01X681819Y116686D02*
G02X685189Y116553I1380J-7807D01*
G01X684887Y115391D02*
G03X682028Y115504I-1689J-6512D01*
G01X677749Y115967D02*
X681819Y116686D01*
G01X682028Y115504D02*
X677958Y114785D01*
G01X676284Y115360D02*
G02X677749Y115967I2101J-2999D01*
G01X677958Y114785D02*
G03X676973Y114377I427J-2424D01*
G01X674779Y114305D02*
X676284Y115360D01*
G01X676973Y114377D02*
X675468Y113322D01*
G01X673794Y113321D02*
G02X674779Y114305I3286J-2305D01*
G01X675468Y113322D02*
G03X674778Y112632I1614J-2304D01*
G01X675468Y113322D02*
G03X674778Y112632I1614J-2304D01*
G01X673794Y113321D02*
G02X674779Y114305I3286J-2305D01*
G01X676973Y114377D02*
X675468Y113322D01*
G01X674779Y114305D02*
X676284Y115360D01*
G01X677958Y114785D02*
G03X676973Y114377I427J-2424D01*
G01X676284Y115360D02*
G02X677749Y115967I2101J-2999D01*
G01X682028Y115504D02*
X677958Y114785D01*
G01X677749Y115967D02*
X681819Y116686D01*
G01X684887Y115391D02*
G03X682028Y115504I-1689J-6512D01*
G01X681819Y116686D02*
G02X685189Y116553I1380J-7807D01*
G01X686588Y114949D02*
X684887Y115391D01*
G01X685189Y116553D02*
X686890Y116111D01*
G01X688135Y114235D02*
G03X686588Y114949I-2754J-3935D01*
G01X686890Y116111D02*
G02X688824Y115219I-1508J-5812D01*
G01X675018Y119278D02*
X671624Y116901D01*
G01X675961Y119669D02*
G03X675018Y119278I410J-2320D01*
G01X675753Y120851D02*
G03X674329Y120261I617J-3503D01*
G01X682346Y120795D02*
X675961Y119669D01*
G01X682138Y121977D02*
X675753Y120851D01*
G01X683818Y120795D02*
G03X682346I-736J-4175D01*
G01X684026Y121977D02*
G03X682138I-944J-5357D01*
G01X689484Y119796D02*
X683818Y120795D01*
G01X689692Y120978D02*
X684026Y121977D01*
G01X690969Y119181D02*
G03X689484Y119796I-2130J-3042D01*
G01X691658Y120165D02*
G03X689692Y120978I-2816J-4027D01*
G01X702498Y111107D02*
X690969Y119181D01*
G01X703187Y112091D02*
X691658Y120165D01*
G01X704892Y110117D02*
G02X702498Y111107I1035J5892D01*
G01X705100Y111299D02*
G02X703187Y112091I829J4709D01*
G01X710656Y109100D02*
X704892Y110117D01*
G01X675018Y119278D02*
X671624Y116901D01*
G01X675753Y120851D02*
G03X674329Y120261I617J-3503D01*
G01X675961Y119669D02*
G03X675018Y119278I410J-2320D01*
G01X682138Y121977D02*
X675753Y120851D01*
G01X682346Y120795D02*
X675961Y119669D01*
G01X684026Y121977D02*
G03X682138I-944J-5357D01*
G01X683818Y120795D02*
G03X682346I-736J-4175D01*
G01X689692Y120978D02*
X684026Y121977D01*
G01X689484Y119796D02*
X683818Y120795D01*
G01X691658Y120165D02*
G03X689692Y120978I-2816J-4027D01*
G01X690969Y119181D02*
G03X689484Y119796I-2130J-3042D01*
G01X703187Y112091D02*
X691658Y120165D01*
G01X702498Y111107D02*
X690969Y119181D01*
G01X705100Y111299D02*
G02X703187Y112091I829J4709D01*
G01X704892Y110117D02*
G02X702498Y111107I1035J5892D01*
G01X710656Y109100D02*
X704892Y110117D01*
G01X684033Y127588D02*
X672080Y125481D01*
G01X672288Y124299D02*
X684242Y126406D01*
G01X686281Y127587D02*
G03X684033Y127588I-1127J-6342D01*
G01X684242Y126406D02*
G02X686071Y126405I912J-5161D01*
G01X690031Y126919D02*
X686281Y127587D01*
G01X686071Y126405D02*
X689820Y125737D01*
G01X692229Y126007D02*
G03X690031Y126919I-3164J-4521D01*
G01X689820Y125737D02*
G02X691540Y125023I-756J-4251D01*
G01X704768Y117224D02*
X692229Y126007D01*
G01X691540Y125023D02*
X704079Y116240D01*
G01X705876Y116764D02*
G02X704768Y117224I483J2727D01*
G01X704079Y116240D02*
G03X705668Y115582I2278J3252D01*
G01X704079Y116240D02*
G03X705668Y115582I2278J3252D01*
G01X705876Y116764D02*
G02X704768Y117224I483J2727D01*
G01X691540Y125023D02*
X704079Y116240D01*
G01X704768Y117224D02*
X692229Y126007D01*
G01X689820Y125737D02*
G02X691540Y125023I-756J-4251D01*
G01X692229Y126007D02*
G03X690031Y126919I-3164J-4521D01*
G01X686071Y126405D02*
X689820Y125737D01*
G01X690031Y126919D02*
X686281Y127587D01*
G01X684242Y126406D02*
G02X686071Y126405I912J-5161D01*
G01X686281Y127587D02*
G03X684033Y127588I-1127J-6342D01*
G01X672288Y124299D02*
X684242Y126406D01*
G01X684033Y127588D02*
X672080Y125481D01*
G01X694257Y832800D02*
Y831838D01*
G01X695457Y832800D02*
Y831839D01*
G01Y832800D02*
Y831839D01*
G01X694257Y832800D02*
Y831838D01*
G01X681659Y832800D02*
Y831842D01*
G01X682859Y832800D02*
Y831842D01*
G01Y832800D02*
Y831842D01*
G01X681659Y832800D02*
Y831842D01*
G01X681684Y882407D02*
Y841431D01*
G01X682885Y882416D02*
Y841428D01*
G01X694282Y882407D02*
Y841431D01*
G01X695483Y882416D02*
Y841428D01*
G01X682885Y882416D02*
Y841428D01*
G01X681684Y882407D02*
Y841431D01*
G01X695483Y882416D02*
Y841428D01*
G01X694282Y882407D02*
Y841431D01*
G01X681659Y832800D02*
Y831842D01*
G01X682859Y832800D02*
Y831842D01*
G01X694257Y832800D02*
Y831838D01*
G01X695457Y832800D02*
Y831839D01*
G01X682859Y832800D02*
Y831842D01*
G01X681659Y832800D02*
Y831842D01*
G01X695457Y832800D02*
Y831839D01*
G01X694257Y832800D02*
Y831838D01*
G01X719379Y80350D02*
X718497D01*
G01X719380Y79150D02*
X718240D01*
G01X718400Y104350D02*
X719079D01*
G01X718500Y103150D02*
X719079D01*
G01X721301Y87400D02*
X719400D01*
G01X721302Y86200D02*
X719400D01*
G01X722669Y87968D02*
G02X721301Y87400I-1370J1368D01*
G01X723518Y87119D02*
G02X721302Y86200I-2218J2217D01*
G01X725945Y91244D02*
X722669Y87968D01*
G01X726794Y90395D02*
X723518Y87119D01*
G01X726641Y92922D02*
G02X725945Y91244I-2373J1D01*
G01X727841Y92921D02*
G02X726794Y90395I-3573J1D01*
G01X726641Y97677D02*
Y92922D01*
G01X727841Y97677D02*
Y92921D01*
G01X727203Y99035D02*
G03X726641Y97677I1358J-1357D01*
G01X728052Y98186D02*
G03X727841Y97677I508J-509D01*
G01X728181Y100013D02*
X727203Y99035D01*
G01X729030Y99163D02*
X728052Y98186D01*
G01X729759Y100666D02*
G03X728181Y100013I0J-2233D01*
G01X729759Y99466D02*
G03X729030Y99163I2J-1032D01*
G01X731545Y100666D02*
X729759D01*
G01X731455Y99466D02*
X729759D01*
G01X719380Y79150D02*
X718240D01*
G01X719379Y80350D02*
X718497D01*
G01X718500Y103150D02*
X719079D01*
G01X718400Y104350D02*
X719079D01*
G01X721302Y86200D02*
X719400D01*
G01X721301Y87400D02*
X719400D01*
G01X723518Y87119D02*
G02X721302Y86200I-2218J2217D01*
G01X722669Y87968D02*
G02X721301Y87400I-1370J1368D01*
G01X726794Y90395D02*
X723518Y87119D01*
G01X725945Y91244D02*
X722669Y87968D01*
G01X727841Y92921D02*
G02X726794Y90395I-3573J1D01*
G01X726641Y92922D02*
G02X725945Y91244I-2373J1D01*
G01X727841Y97677D02*
Y92921D01*
G01X726641Y97677D02*
Y92922D01*
G01X728052Y98186D02*
G03X727841Y97677I508J-509D01*
G01X727203Y99035D02*
G03X726641Y97677I1358J-1357D01*
G01X729030Y99163D02*
X728052Y98186D01*
G01X728181Y100013D02*
X727203Y99035D01*
G01X729759Y99466D02*
G03X729030Y99163I2J-1032D01*
G01X729759Y100666D02*
G03X728181Y100013I0J-2233D01*
G01X731455Y99466D02*
X729759D01*
G01X731545Y100666D02*
X729759D01*
G01X719379Y80350D02*
X718497D01*
G01X719380Y79150D02*
X718240D01*
G01X718400Y104350D02*
X719079D01*
G01X718500Y103150D02*
X719079D01*
G01X721301Y87400D02*
X719400D01*
G01X721302Y86200D02*
X719400D01*
G01X722669Y87968D02*
G02X721301Y87400I-1370J1368D01*
G01X723518Y87119D02*
G02X721302Y86200I-2218J2217D01*
G01X725945Y91244D02*
X722669Y87968D01*
G01X726794Y90395D02*
X723518Y87119D01*
G01X726641Y92922D02*
G02X725945Y91244I-2373J1D01*
G01X727841Y92921D02*
G02X726794Y90395I-3573J1D01*
G01X726641Y97677D02*
Y92922D01*
G01X727841Y97677D02*
Y92921D01*
G01X727203Y99035D02*
G03X726641Y97677I1358J-1357D01*
G01X728052Y98186D02*
G03X727841Y97677I508J-509D01*
G01X728181Y100013D02*
X727203Y99035D01*
G01X729030Y99163D02*
X728052Y98186D01*
G01X729759Y100666D02*
G03X728181Y100013I0J-2233D01*
G01X729759Y99466D02*
G03X729030Y99163I2J-1032D01*
G01X731545Y100666D02*
X729759D01*
G01X731455Y99466D02*
X729759D01*
G01X719380Y79150D02*
X718240D01*
G01X719379Y80350D02*
X718497D01*
G01X718500Y103150D02*
X719079D01*
G01X718400Y104350D02*
X719079D01*
G01X721302Y86200D02*
X719400D01*
G01X721301Y87400D02*
X719400D01*
G01X723518Y87119D02*
G02X721302Y86200I-2218J2217D01*
G01X722669Y87968D02*
G02X721301Y87400I-1370J1368D01*
G01X726794Y90395D02*
X723518Y87119D01*
G01X725945Y91244D02*
X722669Y87968D01*
G01X727841Y92921D02*
G02X726794Y90395I-3573J1D01*
G01X726641Y92922D02*
G02X725945Y91244I-2373J1D01*
G01X727841Y97677D02*
Y92921D01*
G01X726641Y97677D02*
Y92922D01*
G01X728052Y98186D02*
G03X727841Y97677I508J-509D01*
G01X727203Y99035D02*
G03X726641Y97677I1358J-1357D01*
G01X729030Y99163D02*
X728052Y98186D01*
G01X728181Y100013D02*
X727203Y99035D01*
G01X729759Y99466D02*
G03X729030Y99163I2J-1032D01*
G01X729759Y100666D02*
G03X728181Y100013I0J-2233D01*
G01X731455Y99466D02*
X729759D01*
G01X731545Y100666D02*
X729759D01*
G01X707700Y104350D02*
X711100D01*
G01Y103150D02*
X707700D01*
G01X709000Y87350D02*
X710475D01*
G01X709000Y86150D02*
X710474D01*
G01X707375Y88023D02*
G03X709000Y87350I1625J1625D01*
G01X706526Y87174D02*
G03X709000Y86150I2473J2475D01*
G01X705999Y89399D02*
X707375Y88023D01*
G01X705150Y88550D02*
X706526Y87174D01*
G01X711100Y103150D02*
X707700D01*
G01Y104350D02*
X711100D01*
G01X709000Y86150D02*
X710474D01*
G01X709000Y87350D02*
X710475D01*
G01X706526Y87174D02*
G03X709000Y86150I2473J2475D01*
G01X707375Y88023D02*
G03X709000Y87350I1625J1625D01*
G01X705150Y88550D02*
X706526Y87174D01*
G01X705999Y89399D02*
X707375Y88023D01*
G01X718400Y116350D02*
X719056D01*
G01X718500Y115150D02*
X719136D01*
G01X718500D02*
X719136D01*
G01X718400Y116350D02*
X719056D01*
G01X718400D02*
X719056D01*
G01X718500Y115150D02*
X719136D01*
G01X718500D02*
X719136D01*
G01X718400Y116350D02*
X719056D01*
G01X710864Y110282D02*
X705100Y111299D01*
G01X712946Y108900D02*
G02X710656Y109100I-2J13190D01*
G01X712945Y110100D02*
G02X710864Y110282I0J11990D01*
G01X727218Y108900D02*
X712946D01*
G01X727218Y110100D02*
X712945D01*
G01X728739Y109530D02*
G02X727218Y108900I-1521J1521D01*
G01X727890Y110379D02*
G02X727218Y110100I-673J672D01*
G01X729787Y110578D02*
X728739Y109530D01*
G01X728938Y111427D02*
X727890Y110379D01*
G01X731121Y111131D02*
G03X729787Y110578I1J-1887D01*
G01X731121Y112331D02*
G03X728938Y111427I0J-3088D01*
G01X734145Y111131D02*
X731121D01*
G01X734145Y112331D02*
X731121D01*
G01X710864Y110282D02*
X705100Y111299D01*
G01X712945Y110100D02*
G02X710864Y110282I0J11990D01*
G01X712946Y108900D02*
G02X710656Y109100I-2J13190D01*
G01X727218Y110100D02*
X712945D01*
G01X727218Y108900D02*
X712946D01*
G01X727890Y110379D02*
G02X727218Y110100I-673J672D01*
G01X728739Y109530D02*
G02X727218Y108900I-1521J1521D01*
G01X728938Y111427D02*
X727890Y110379D01*
G01X729787Y110578D02*
X728739Y109530D01*
G01X731121Y112331D02*
G03X728938Y111427I0J-3088D01*
G01X731121Y111131D02*
G03X729787Y110578I1J-1887D01*
G01X734145Y112331D02*
X731121D01*
G01X734145Y111131D02*
X731121D01*
G01X708226Y116350D02*
X705876Y116764D01*
G01X705668Y115582D02*
X708121Y115150D01*
G01X711500Y116350D02*
X708226D01*
G01X708121Y115150D02*
X711500D01*
G01X708121D02*
X711500D01*
G01Y116350D02*
X708226D01*
G01X705668Y115582D02*
X708121Y115150D01*
G01X708226Y116350D02*
X705876Y116764D01*
G01X725753Y832800D02*
Y831828D01*
G01X726953Y832800D02*
Y831829D01*
G01X738352Y832800D02*
Y831826D01*
G01X726953Y832800D02*
Y831829D01*
G01X725753Y832800D02*
Y831828D01*
G01X738352Y832800D02*
Y831826D01*
G01X738377Y882407D02*
Y841431D01*
G01X738352Y832800D02*
Y831826D01*
G01X725778Y882407D02*
Y841428D01*
G01X726979Y882416D02*
Y841428D01*
G01X738377Y882407D02*
Y841431D01*
G01X726979Y882416D02*
Y841428D01*
G01X725778Y882407D02*
Y841428D01*
G01X725753Y832800D02*
Y831828D01*
G01X726953Y832800D02*
Y831829D01*
G01X738352Y832800D02*
Y831826D01*
G01X726953Y832800D02*
Y831829D01*
G01X725753Y832800D02*
Y831828D01*
G01X739552Y832800D02*
Y831826D01*
G01X750950Y832800D02*
Y831821D01*
G01X752150Y832800D02*
Y831861D01*
G01X763549Y832800D02*
Y831918D01*
G01X764749Y832800D02*
Y831918D01*
G01X739552Y832800D02*
Y831826D01*
G01X752150Y832800D02*
Y831861D01*
G01X750950Y832800D02*
Y831821D01*
G01X764749Y832800D02*
Y831918D01*
G01X763549Y832800D02*
Y831918D01*
G01X750975Y882407D02*
Y841428D01*
G01X752176Y882416D02*
Y841428D01*
G01X763574Y882407D02*
Y841431D01*
G01X764775Y882416D02*
Y841428D01*
G01X739578Y882416D02*
Y841428D01*
G01X752176Y882416D02*
Y841428D01*
G01X750975Y882407D02*
Y841428D01*
G01X764775Y882416D02*
Y841428D01*
G01X763574Y882407D02*
Y841431D01*
G01X750950Y832800D02*
Y831821D01*
G01X752150Y832800D02*
Y831861D01*
G01X763549Y832800D02*
Y831918D01*
G01X764749Y832800D02*
Y831918D01*
G01X739552Y832800D02*
Y831826D01*
G01X752150Y832800D02*
Y831861D01*
G01X750950Y832800D02*
Y831821D01*
G01X764749Y832800D02*
Y831918D01*
G01X763549Y832800D02*
Y831918D01*
G01X739578Y882416D02*
Y841428D01*
G01X739552Y832800D02*
Y831826D01*
G01X786413Y174963D02*
X785719Y178224D01*
G01X786819Y178821D02*
X787541Y175431D01*
G01X790929Y168013D02*
X786413Y174963D01*
G01X787541Y175431D02*
X791936Y168667D01*
G01X792422Y166521D02*
G02X790929Y168013I2760J4255D01*
G01X791936Y168667D02*
G03X793075Y167528I3247J2108D01*
G01X801969Y160324D02*
X792422Y166521D01*
G01X793075Y167528D02*
X802436Y161452D01*
G01X802187Y160277D02*
X801969Y160324D01*
G01X802436Y161452D02*
X810109Y159820D01*
G01X810143Y158585D02*
X802187Y160278D01*
G01X802436Y161452D02*
X810109Y159820D01*
G01X802436Y161452D02*
X810109Y159820D01*
G01X802187Y160277D02*
X801969Y160324D01*
G01X810143Y158585D02*
X802187Y160278D01*
G01X793075Y167528D02*
X802436Y161452D01*
G01X801969Y160324D02*
X792422Y166521D01*
G01X791936Y168667D02*
G03X793075Y167528I3247J2108D01*
G01X792422Y166521D02*
G02X790929Y168013I2760J4255D01*
G01X787541Y175431D02*
X791936Y168667D01*
G01X790929Y168013D02*
X786413Y174963D01*
G01X786819Y178821D02*
X787541Y175431D01*
G01X786413Y174963D02*
X785719Y178224D01*
G01X803167Y168133D02*
X814335Y165758D01*
G01X803633Y169261D02*
X809978Y167912D01*
G01X801762Y169044D02*
X803167Y168133D01*
G01X802630Y169912D02*
X803633Y169261D01*
G01X800121Y171572D02*
X801762Y169044D01*
G01X801236Y172060D02*
X802630Y169912D01*
G01X799073Y175700D02*
X800121Y171572D01*
G01X800188Y176188D02*
X801236Y172060D01*
G01X803167Y168133D02*
X814335Y165758D01*
G01X803633Y169261D02*
X809978Y167912D01*
G01X803167Y168133D02*
X814335Y165758D01*
G01X802630Y169912D02*
X803633Y169261D01*
G01X801762Y169044D02*
X803167Y168133D01*
G01X801236Y172060D02*
X802630Y169912D01*
G01X800121Y171572D02*
X801762Y169044D01*
G01X800188Y176188D02*
X801236Y172060D01*
G01X799073Y175700D02*
X800121Y171572D01*
G01X786413Y174963D02*
X785719Y178224D01*
G01X786819Y178821D02*
X787541Y175431D01*
G01X790929Y168013D02*
X786413Y174963D01*
G01X787541Y175431D02*
X791936Y168667D01*
G01X792422Y166521D02*
G02X790929Y168013I2760J4255D01*
G01X791936Y168667D02*
G03X793075Y167528I3247J2108D01*
G01X801969Y160324D02*
X792422Y166521D01*
G01X793075Y167528D02*
X802436Y161452D01*
G01X802187Y160277D02*
X801969Y160324D01*
G01X802436Y161452D02*
X810109Y159820D01*
G01X810143Y158585D02*
X802187Y160278D01*
G01X802436Y161452D02*
X810109Y159820D01*
G01X802436Y161452D02*
X810109Y159820D01*
G01X802187Y160277D02*
X801969Y160324D01*
G01X810143Y158585D02*
X802187Y160278D01*
G01X793075Y167528D02*
X802436Y161452D01*
G01X801969Y160324D02*
X792422Y166521D01*
G01X791936Y168667D02*
G03X793075Y167528I3247J2108D01*
G01X792422Y166521D02*
G02X790929Y168013I2760J4255D01*
G01X787541Y175431D02*
X791936Y168667D01*
G01X790929Y168013D02*
X786413Y174963D01*
G01X786819Y178821D02*
X787541Y175431D01*
G01X786413Y174963D02*
X785719Y178224D01*
G01X803167Y168133D02*
X814335Y165758D01*
G01X803633Y169261D02*
X809978Y167912D01*
G01X801762Y169044D02*
X803167Y168133D01*
G01X802630Y169912D02*
X803633Y169261D01*
G01X800121Y171572D02*
X801762Y169044D01*
G01X801236Y172060D02*
X802630Y169912D01*
G01X799073Y175700D02*
X800121Y171572D01*
G01X800188Y176188D02*
X801236Y172060D01*
G01X803167Y168133D02*
X814335Y165758D01*
G01X803633Y169261D02*
X809978Y167912D01*
G01X803167Y168133D02*
X814335Y165758D01*
G01X802630Y169912D02*
X803633Y169261D01*
G01X801762Y169044D02*
X803167Y168133D01*
G01X801236Y172060D02*
X802630Y169912D01*
G01X800121Y171572D02*
X801762Y169044D01*
G01X800188Y176188D02*
X801236Y172060D01*
G01X799073Y175700D02*
X800121Y171572D01*
G01X797793Y184835D02*
X812802Y181645D01*
G01Y182872D02*
X798260Y185963D01*
G01X790604Y189499D02*
X797793Y184835D01*
G01X798260Y185963D02*
X791472Y190367D01*
G01X789556Y191113D02*
X790604Y189499D01*
G01X791472Y190367D02*
X790684Y191580D01*
G01X789250Y192555D02*
X789556Y191113D01*
G01X790684Y191580D02*
X790450Y192682D01*
G01X789250Y193945D02*
Y192555D01*
G01X790450Y192682D02*
Y193900D01*
G01Y192682D02*
Y193900D01*
G01X789250Y193945D02*
Y192555D01*
G01X790684Y191580D02*
X790450Y192682D01*
G01X789250Y192555D02*
X789556Y191113D01*
G01X791472Y190367D02*
X790684Y191580D01*
G01X789556Y191113D02*
X790604Y189499D01*
G01X798260Y185963D02*
X791472Y190367D01*
G01X790604Y189499D02*
X797793Y184835D01*
G01X812802Y182872D02*
X798260Y185963D01*
G01X797793Y184835D02*
X812802Y181645D01*
G01X782873Y181072D02*
X780235D01*
G01X780614Y182272D02*
X783371D01*
G01X785719Y178224D02*
X782873Y181072D01*
G01X783371Y182272D02*
X786819Y178821D01*
G01X783371Y182272D02*
X786819Y178821D01*
G01X785719Y178224D02*
X782873Y181072D01*
G01X780614Y182272D02*
X783371D01*
G01X782873Y181072D02*
X780235D01*
G01X798298Y176892D02*
X799073Y175700D01*
G01X799165Y177760D02*
X800188Y176188D01*
G01X796986Y177743D02*
X798298Y176892D01*
G01X797342Y178943D02*
X799165Y177760D01*
G01X794360Y177743D02*
X796986D01*
G01X794360Y178943D02*
X797342D01*
G01X799165Y177760D02*
X800188Y176188D01*
G01X798298Y176892D02*
X799073Y175700D01*
G01X797342Y178943D02*
X799165Y177760D01*
G01X796986Y177743D02*
X798298Y176892D01*
G01X794360Y178943D02*
X797342D01*
G01X794360Y177743D02*
X796986D01*
G01X797793Y184835D02*
X812802Y181645D01*
G01Y182872D02*
X798260Y185963D01*
G01X790604Y189499D02*
X797793Y184835D01*
G01X798260Y185963D02*
X791472Y190367D01*
G01X789556Y191113D02*
X790604Y189499D01*
G01X791472Y190367D02*
X790684Y191580D01*
G01X789250Y192555D02*
X789556Y191113D01*
G01X790684Y191580D02*
X790450Y192682D01*
G01X789250Y193945D02*
Y192555D01*
G01X790450Y192682D02*
Y193900D01*
G01Y192682D02*
Y193900D01*
G01X789250Y193945D02*
Y192555D01*
G01X790684Y191580D02*
X790450Y192682D01*
G01X789250Y192555D02*
X789556Y191113D01*
G01X791472Y190367D02*
X790684Y191580D01*
G01X789556Y191113D02*
X790604Y189499D01*
G01X798260Y185963D02*
X791472Y190367D01*
G01X790604Y189499D02*
X797793Y184835D01*
G01X812802Y182872D02*
X798260Y185963D01*
G01X797793Y184835D02*
X812802Y181645D01*
G01X782873Y181072D02*
X780235D01*
G01X780614Y182272D02*
X783371D01*
G01X785719Y178224D02*
X782873Y181072D01*
G01X783371Y182272D02*
X786819Y178821D01*
G01X783371Y182272D02*
X786819Y178821D01*
G01X785719Y178224D02*
X782873Y181072D01*
G01X780614Y182272D02*
X783371D01*
G01X782873Y181072D02*
X780235D01*
G01X798298Y176892D02*
X799073Y175700D01*
G01X799165Y177760D02*
X800188Y176188D01*
G01X796986Y177743D02*
X798298Y176892D01*
G01X797342Y178943D02*
X799165Y177760D01*
G01X794360Y177743D02*
X796986D01*
G01X794360Y178943D02*
X797342D01*
G01X799165Y177760D02*
X800188Y176188D01*
G01X798298Y176892D02*
X799073Y175700D01*
G01X797342Y178943D02*
X799165Y177760D01*
G01X796986Y177743D02*
X798298Y176892D01*
G01X794360Y178943D02*
X797342D01*
G01X794360Y177743D02*
X796986D01*
G01X776147Y832800D02*
Y831828D01*
G01X777347Y832800D02*
Y831829D01*
G01X788745Y832800D02*
Y831909D01*
G01X789945Y832800D02*
Y831908D01*
G01X801344Y832800D02*
Y831806D01*
G01X802544Y832800D02*
Y831845D01*
G01X777347Y832800D02*
Y831829D01*
G01X776147Y832800D02*
Y831828D01*
G01X789945Y832800D02*
Y831908D01*
G01X788745Y832800D02*
Y831909D01*
G01X802544Y832800D02*
Y831845D01*
G01X801344Y832800D02*
Y831806D01*
G01X776172Y882407D02*
Y841431D01*
G01X777373Y882416D02*
Y841428D01*
G01X788770Y882407D02*
Y841431D01*
G01X789971Y882416D02*
Y841428D01*
G01X801369Y882407D02*
Y841431D01*
G01X802570Y882416D02*
Y841428D01*
G01X777373Y882416D02*
Y841428D01*
G01X776172Y882407D02*
Y841431D01*
G01X789971Y882416D02*
Y841428D01*
G01X788770Y882407D02*
Y841431D01*
G01X802570Y882416D02*
Y841428D01*
G01X801369Y882407D02*
Y841431D01*
G01X776147Y832800D02*
Y831828D01*
G01X777347Y832800D02*
Y831829D01*
G01X788745Y832800D02*
Y831909D01*
G01X789945Y832800D02*
Y831908D01*
G01X801344Y832800D02*
Y831806D01*
G01X802544Y832800D02*
Y831845D01*
G01X777347Y832800D02*
Y831829D01*
G01X776147Y832800D02*
Y831828D01*
G01X789945Y832800D02*
Y831908D01*
G01X788745Y832800D02*
Y831909D01*
G01X802544Y832800D02*
Y831845D01*
G01X801344Y832800D02*
Y831806D01*
G01X813025Y159365D02*
X810143Y158585D01*
G01X810109Y159820D02*
X812865Y160565D01*
G01X834111Y159365D02*
X813025D01*
G01X812865Y160565D02*
X834110D01*
G01X812865D02*
X834110D01*
G01X834111Y159365D02*
X813025D01*
G01X810109Y159820D02*
X812865Y160565D01*
G01X813025Y159365D02*
X810143Y158585D01*
G01X814335Y165758D02*
X855277Y174592D01*
G01X814333Y166986D02*
X855149Y175792D01*
G01X812754Y167322D02*
X814333Y166986D01*
G01D02*
X855149Y175792D01*
G01X814335Y165758D02*
X855277Y174592D01*
G01X812754Y167322D02*
X814333Y166986D01*
G01X813025Y159365D02*
X810143Y158585D01*
G01X810109Y159820D02*
X812865Y160565D01*
G01X834111Y159365D02*
X813025D01*
G01X812865Y160565D02*
X834110D01*
G01X812865D02*
X834110D01*
G01X834111Y159365D02*
X813025D01*
G01X810109Y159820D02*
X812865Y160565D01*
G01X813025Y159365D02*
X810143Y158585D01*
G01X814335Y165758D02*
X855277Y174592D01*
G01X814333Y166986D02*
X855149Y175792D01*
G01X812754Y167322D02*
X814333Y166986D01*
G01D02*
X855149Y175792D01*
G01X814335Y165758D02*
X855277Y174592D01*
G01X812754Y167322D02*
X814333Y166986D01*
G01X812802Y181645D02*
X847414Y189003D01*
G01Y190230D02*
X812802Y182872D01*
G01X847414Y190230D02*
X812802Y182872D01*
G01Y181645D02*
X847414Y189003D01*
G01X812802Y181645D02*
X847414Y189003D01*
G01Y190230D02*
X812802Y182872D01*
G01X847414Y190230D02*
X812802Y182872D01*
G01Y181645D02*
X847414Y189003D01*
G01X813942Y832800D02*
Y831901D01*
G01X815142Y832800D02*
Y831955D01*
G01X839139Y832800D02*
Y831894D01*
G01X815142Y832800D02*
Y831955D01*
G01X813942Y832800D02*
Y831901D01*
G01X839139Y832800D02*
Y831894D01*
G01X839164Y882407D02*
Y841431D01*
G01X839139Y832800D02*
Y831894D01*
G01X813967Y882407D02*
Y841431D01*
G01X815168Y882416D02*
Y841428D01*
G01X839164Y882407D02*
Y841431D01*
G01X815168Y882416D02*
Y841428D01*
G01X813967Y882407D02*
Y841431D01*
G01X813942Y832800D02*
Y831901D01*
G01X815142Y832800D02*
Y831955D01*
G01X839139Y832800D02*
Y831894D01*
G01X815142Y832800D02*
Y831955D01*
G01X813942Y832800D02*
Y831901D01*
G01X864154Y160992D02*
X871897Y168735D01*
G01X863305Y161841D02*
X871048Y169584D01*
G01X860225Y159365D02*
G03X864154Y160992I1J5556D01*
G01X860225Y160565D02*
G03X863305Y161841I0J4355D01*
G01X839861Y159365D02*
X860225D01*
G01X855963Y160565D02*
X860225D01*
G01X851511D02*
X853125D01*
G01X847059D02*
X848673D01*
G01X839862D02*
X844221D01*
G01X863305Y161841D02*
X871048Y169584D01*
G01X864154Y160992D02*
X871897Y168735D01*
G01X860225Y160565D02*
G03X863305Y161841I0J4355D01*
G01X860225Y159365D02*
G03X864154Y160992I1J5556D01*
G01X855963Y160565D02*
X860225D01*
G01X839861Y159365D02*
X860225D01*
G01X851511Y160565D02*
X853125D01*
G01X839861Y159365D02*
X860225D01*
G01X847059Y160565D02*
X848673D01*
G01X839861Y159365D02*
X860225D01*
G01X839862Y160565D02*
X844221D01*
G01X839861Y159365D02*
X860225D01*
G01X855277Y174592D02*
X871300D01*
G01X855277D02*
X871300D01*
G01X855277D02*
X871300D01*
G01X855277D02*
X871300D01*
G01X871698Y178835D02*
X878779D01*
G01X879004Y180035D02*
X871907D01*
G01X861275Y186013D02*
X871389Y178932D01*
G01X871907Y180035D02*
X861673Y187200D01*
G01X858530Y186640D02*
X861078Y186099D01*
G01X861673Y187200D02*
X856124Y188379D01*
G01X856662Y187037D02*
X858530Y186640D01*
G01X861673Y187200D02*
X856124Y188379D01*
G01X847414Y189003D02*
X856662Y187037D01*
G01X848993Y189895D02*
X847414Y190230D01*
G01X853348Y188969D02*
X851769Y189305D01*
G01X848993Y189895D02*
X847414Y190230D01*
G01Y189003D02*
X856662Y187037D01*
G01X853348Y188969D02*
X851769Y189305D01*
G01X847414Y189003D02*
X856662Y187037D01*
G01X861673Y187200D02*
X856124Y188379D01*
G01X858530Y186640D02*
X861078Y186099D01*
G01X856662Y187037D02*
X858530Y186640D01*
G01X871907Y180035D02*
X861673Y187200D01*
G01X861275Y186013D02*
X871389Y178932D01*
G01X879004Y180035D02*
X871907D01*
G01X871698Y178835D02*
X878779D01*
G01X855149Y175792D02*
X871300D01*
G01X855149D02*
X871300D01*
G01X871698Y178835D02*
X878779D01*
G01X879004Y180035D02*
X871907D01*
G01X861275Y186013D02*
X871389Y178932D01*
G01X871907Y180035D02*
X861673Y187200D01*
G01X858530Y186640D02*
X861078Y186099D01*
G01X861673Y187200D02*
X856124Y188379D01*
G01X856662Y187037D02*
X858530Y186640D01*
G01X861673Y187200D02*
X856124Y188379D01*
G01X847414Y189003D02*
X856662Y187037D01*
G01X848993Y189895D02*
X847414Y190230D01*
G01X853348Y188969D02*
X851769Y189305D01*
G01X848993Y189895D02*
X847414Y190230D01*
G01Y189003D02*
X856662Y187037D01*
G01X853348Y188969D02*
X851769Y189305D01*
G01X847414Y189003D02*
X856662Y187037D01*
G01X861673Y187200D02*
X856124Y188379D01*
G01X858530Y186640D02*
X861078Y186099D01*
G01X856662Y187037D02*
X858530Y186640D01*
G01X871907Y180035D02*
X861673Y187200D01*
G01X861275Y186013D02*
X871389Y178932D01*
G01X879004Y180035D02*
X871907D01*
G01X871698Y178835D02*
X878779D01*
G01X855149Y175792D02*
X871300D01*
G01X855149D02*
X871300D01*
G01X840339Y832800D02*
Y831894D01*
G01X851737Y832800D02*
Y831789D01*
G01X852937Y832800D02*
Y831789D01*
G01X840339Y832800D02*
Y831894D01*
G01X852937Y832800D02*
Y831789D01*
G01X851737Y832800D02*
Y831789D01*
G01X851762Y882407D02*
Y841431D01*
G01X852963Y882416D02*
Y841428D01*
G01X840365Y882416D02*
Y841428D01*
G01X852963Y882416D02*
Y841428D01*
G01X851762Y882407D02*
Y841431D01*
G01X851737Y832800D02*
Y831789D01*
G01X852937Y832800D02*
Y831789D01*
G01X840339Y832800D02*
Y831894D01*
G01X852937Y832800D02*
Y831789D01*
G01X851737Y832800D02*
Y831789D01*
G01X840365Y882416D02*
Y841428D01*
G01X840339Y832800D02*
Y831894D01*
G01X1072900Y58200D02*
X1075300D01*
G01X1072900Y59400D02*
X1075300D01*
G01X1070496Y52074D02*
X1074700D01*
G01X1074640Y50874D02*
X1070495D01*
G01X1063932Y54793D02*
G03X1070496Y52074I6564J6564D01*
G01X1070495Y50874D02*
G02X1063083Y53944I0J10483D01*
G01X1059731Y56661D02*
G02X1063932Y54793I-330J-6399D01*
G01X1063083Y53944D02*
G03X1059400Y55470I-3683J-3682D01*
G01X1059285Y56684D02*
X1059731Y56661D01*
G01X1059400Y55470D02*
X1058624D01*
G01X1072900Y59400D02*
X1075300D01*
G01X1072900Y58200D02*
X1075300D01*
G01X1059400Y55470D02*
X1058624D01*
G01X1059285Y56684D02*
X1059731Y56661D01*
G01X1063083Y53944D02*
G03X1059400Y55470I-3683J-3682D01*
G01X1059731Y56661D02*
G02X1063932Y54793I-330J-6399D01*
G01X1070495Y50874D02*
G02X1063083Y53944I0J10483D01*
G01X1063932Y54793D02*
G03X1070496Y52074I6564J6564D01*
G01X1074640Y50874D02*
X1070495D01*
G01X1070496Y52074D02*
X1074700D01*
G01X1072900Y58200D02*
X1075300D01*
G01X1072900Y59400D02*
X1075300D01*
G01X1070496Y52074D02*
X1074700D01*
G01X1074640Y50874D02*
X1070495D01*
G01X1063932Y54793D02*
G03X1070496Y52074I6564J6564D01*
G01X1070495Y50874D02*
G02X1063083Y53944I0J10483D01*
G01X1059731Y56661D02*
G02X1063932Y54793I-330J-6399D01*
G01X1063083Y53944D02*
G03X1059400Y55470I-3683J-3682D01*
G01X1059285Y56684D02*
X1059731Y56661D01*
G01X1059400Y55470D02*
X1058624D01*
G01X1072900Y59400D02*
X1075300D01*
G01X1072900Y58200D02*
X1075300D01*
G01X1059400Y55470D02*
X1058624D01*
G01X1059285Y56684D02*
X1059731Y56661D01*
G01X1063083Y53944D02*
G03X1059400Y55470I-3683J-3682D01*
G01X1059731Y56661D02*
G02X1063932Y54793I-330J-6399D01*
G01X1070495Y50874D02*
G02X1063083Y53944I0J10483D01*
G01X1063932Y54793D02*
G03X1070496Y52074I6564J6564D01*
G01X1074640Y50874D02*
X1070495D01*
G01X1070496Y52074D02*
X1074700D01*
G01X1054912Y882407D02*
Y841431D01*
G01X1056113Y882416D02*
Y841428D01*
G01X1067511Y882407D02*
Y841431D01*
G01X1068712Y882416D02*
Y841428D01*
G01X1043515Y882416D02*
Y841428D01*
G01X1042314Y882407D02*
Y841431D01*
G01X1056113Y882416D02*
Y841428D01*
G01X1054912Y882407D02*
Y841431D01*
G01X1068712Y882416D02*
Y841428D01*
G01X1067511Y882407D02*
Y841431D01*
G01X1054887Y832800D02*
Y831910D01*
G01X1056087Y832800D02*
Y831949D01*
G01X1067486Y832800D02*
Y831900D01*
G01X1068686Y832800D02*
Y831852D01*
G01X1043489Y832800D02*
Y831799D01*
G01X1042289Y832800D02*
Y831800D01*
G01X1056087Y832800D02*
Y831949D01*
G01X1054887Y832800D02*
Y831910D01*
G01X1068686Y832800D02*
Y831852D01*
G01X1067486Y832800D02*
Y831900D01*
G01X1042314Y882407D02*
Y841431D01*
G01X1043515Y882416D02*
Y841428D01*
G01X1042289Y832800D02*
Y831800D01*
G01X1043489Y832800D02*
Y831799D01*
G01X1042289Y832800D02*
Y831800D01*
G01X1043489Y832800D02*
Y831799D01*
G01X1054887Y832800D02*
Y831910D01*
G01X1056087Y832800D02*
Y831949D01*
G01X1067486Y832800D02*
Y831900D01*
G01X1068686Y832800D02*
Y831852D01*
G01X1043489Y832800D02*
Y831799D01*
G01X1042289Y832800D02*
Y831800D01*
G01X1056087Y832800D02*
Y831949D01*
G01X1054887Y832800D02*
Y831910D01*
G01X1068686Y832800D02*
Y831852D01*
G01X1067486Y832800D02*
Y831900D01*
G01X1091309Y17393D02*
X1152579D01*
G01X1091991Y16193D02*
X1153077D01*
G01X1091991D02*
X1153077D01*
G01X1091309Y17393D02*
X1152579D01*
G01X1085668Y58200D02*
X1082247D01*
G01X1085668Y59400D02*
X1082906D01*
G01X1092550Y61050D02*
G02X1085668Y58200I-6881J6882D01*
G01X1091701Y61899D02*
G02X1085668Y59400I-6033J6033D01*
G01X1094348Y65391D02*
G02X1092550Y61050I-6140J0D01*
G01X1093148Y65392D02*
G02X1091701Y61899I-4940J0D01*
G01X1094348Y92944D02*
Y65391D01*
G01X1093148Y92945D02*
Y65392D01*
G01X1092073Y52350D02*
X1083026D01*
G01X1092073Y51150D02*
X1083026D01*
G01X1093317Y52865D02*
G02X1092073Y52350I-1244J1245D01*
G01X1094166Y52016D02*
G02X1092073Y51150I-2092J2094D01*
G01X1114527Y74075D02*
X1093317Y52865D01*
G01X1115376Y73226D02*
X1094166Y52016D01*
G01X1085668Y59400D02*
X1082906D01*
G01X1085668Y58200D02*
X1082247D01*
G01X1091701Y61899D02*
G02X1085668Y59400I-6033J6033D01*
G01X1092550Y61050D02*
G02X1085668Y58200I-6881J6882D01*
G01X1093148Y65392D02*
G02X1091701Y61899I-4940J0D01*
G01X1094348Y65391D02*
G02X1092550Y61050I-6140J0D01*
G01X1093148Y92945D02*
Y65392D01*
G01X1094348Y92944D02*
Y65391D01*
G01X1092073Y51150D02*
X1083026D01*
G01X1092073Y52350D02*
X1083026D01*
G01X1094166Y52016D02*
G02X1092073Y51150I-2092J2094D01*
G01X1093317Y52865D02*
G02X1092073Y52350I-1244J1245D01*
G01X1115376Y73226D02*
X1094166Y52016D01*
G01X1114527Y74075D02*
X1093317Y52865D01*
G01X1095038Y96410D02*
G03X1094348Y92944I8364J-3467D01*
G01X1093929Y96869D02*
G03X1093148Y92945I9473J-3925D01*
G01X1095505Y97538D02*
X1095038Y96410D01*
G01X1094396Y97997D02*
X1093929Y96869D01*
G01X1097703Y99838D02*
G03X1095505Y97538I1864J-3982D01*
G01X1097194Y100925D02*
G03X1094396Y97997I2373J-5069D01*
G01X1101603Y101662D02*
X1097703Y99838D01*
G01X1099144Y101837D02*
X1097194Y100925D01*
G01X1101094Y102750D02*
X1099144Y101837D01*
G01X1105919Y102622D02*
G03X1101603Y101662I1J-10186D01*
G01X1105918Y103822D02*
G03X1101094Y102750I-1J-11386D01*
G01X1136195Y102622D02*
X1105919D01*
G01X1136196Y103822D02*
X1105918D01*
G01X1093929Y96869D02*
G03X1093148Y92945I9473J-3925D01*
G01X1095038Y96410D02*
G03X1094348Y92944I8364J-3467D01*
G01X1094396Y97997D02*
X1093929Y96869D01*
G01X1095505Y97538D02*
X1095038Y96410D01*
G01X1097194Y100925D02*
G03X1094396Y97997I2373J-5069D01*
G01X1097703Y99838D02*
G03X1095505Y97538I1864J-3982D01*
G01X1099144Y101837D02*
X1097194Y100925D01*
G01X1101603Y101662D02*
X1097703Y99838D01*
G01X1101094Y102750D02*
X1099144Y101837D01*
G01X1101603Y101662D02*
X1097703Y99838D01*
G01X1105918Y103822D02*
G03X1101094Y102750I-1J-11386D01*
G01X1105919Y102622D02*
G03X1101603Y101662I1J-10186D01*
G01X1136196Y103822D02*
X1105918D01*
G01X1136195Y102622D02*
X1105919D01*
G01X1080109Y882407D02*
Y841431D01*
G01X1081310Y882416D02*
Y841428D01*
G01X1092707Y882407D02*
Y841431D01*
G01X1093908Y882416D02*
Y841428D01*
G01X1105306Y882407D02*
Y841431D01*
G01X1106507Y882416D02*
Y841428D01*
G01X1081310Y882416D02*
Y841428D01*
G01X1080109Y882407D02*
Y841431D01*
G01X1093908Y882416D02*
Y841428D01*
G01X1092707Y882407D02*
Y841431D01*
G01X1106507Y882416D02*
Y841428D01*
G01X1105306Y882407D02*
Y841431D01*
G01X1080084Y832800D02*
Y831800D01*
G01X1081284Y832800D02*
Y831799D01*
G01X1092682Y832800D02*
Y831800D01*
G01X1093882Y832800D02*
Y831799D01*
G01X1105281Y832800D02*
Y831800D01*
G01X1106481Y832800D02*
Y831799D01*
G01X1081284Y832800D02*
Y831799D01*
G01X1080084Y832800D02*
Y831800D01*
G01X1093882Y832800D02*
Y831799D01*
G01X1092682Y832800D02*
Y831800D01*
G01X1106481Y832800D02*
Y831799D01*
G01X1105281Y832800D02*
Y831800D01*
G01X1092682Y832800D02*
Y831800D01*
G01X1093882Y832800D02*
Y831799D01*
G01X1105281Y832800D02*
Y831800D01*
G01X1106481Y832800D02*
Y831799D01*
G01X1093882Y832800D02*
Y831799D01*
G01X1092682Y832800D02*
Y831800D01*
G01X1106481Y832800D02*
Y831799D01*
G01X1105281Y832800D02*
Y831800D01*
G01X1080084Y832800D02*
Y831800D01*
G01X1081284Y832800D02*
Y831799D01*
G01Y832800D02*
Y831799D01*
G01X1080084Y832800D02*
Y831800D01*
G01X1118041Y75530D02*
G03X1114527Y74075I-1J-4969D01*
G01X1118041Y74330D02*
G03X1115376Y73226I0J-3769D01*
G01X1118041Y74330D02*
G03X1115376Y73226I0J-3769D01*
G01X1118041Y75530D02*
G03X1114527Y74075I-1J-4969D01*
G01X1146320Y102782D02*
X1135008Y114094D01*
G01X1147169Y103631D02*
X1135857Y114943D01*
G01X1147169Y103631D02*
X1135857Y114943D01*
G01X1146320Y102782D02*
X1135008Y114094D01*
G01X1137466Y102095D02*
G03X1136195Y102622I-1272J-1271D01*
G01X1138315Y102944D02*
G03X1136196Y103822I-2120J-2120D01*
G01X1139193Y100824D02*
G03X1138315Y102944I-2998J0D01*
G01X1137993Y100824D02*
G03X1137466Y102095I-1798J-1D01*
G01X1138315Y102944D02*
G03X1136196Y103822I-2120J-2120D01*
G01X1139193Y100824D02*
G03X1138315Y102944I-2998J0D01*
G01X1137993Y99499D02*
Y100824D01*
G01X1139193Y99500D02*
Y100824D01*
G01X1137836Y98520D02*
G03X1137992Y99499I-2966J975D01*
G01X1138976Y98145D02*
G03X1139193Y99500I-4106J1352D01*
G01X1138741Y97573D02*
G03X1138976Y98145I-3871J1924D01*
G01X1137666Y98107D02*
G03X1137836Y98520I-2795J1392D01*
G01X1138976Y98145D02*
G03X1139193Y99500I-4106J1352D01*
G01X1138741Y97573D02*
G03X1138976Y98145I-3871J1924D01*
G01X1137079Y97292D02*
G03X1137666Y98108I-2208J2208D01*
G01X1138741Y97573D02*
G03X1138976Y98145I-3871J1924D01*
G01X1130508Y75530D02*
X1118041D01*
G01X1130508Y74330D02*
X1118041D01*
G01X1132159Y76214D02*
G02X1130508Y75530I-1651J1651D01*
G01X1133008Y75365D02*
G02X1130508Y74330I-2499J2500D01*
G01X1132902Y76957D02*
X1132159Y76214D01*
G01X1133751Y76108D02*
X1133008Y75365D01*
G01X1133704Y78893D02*
G02X1132902Y76957I-2738J0D01*
G01X1134904Y78892D02*
G02X1133751Y76108I-3938J0D01*
G01X1134299Y80341D02*
G03X1133704Y78904I1438J-1437D01*
G01X1135149Y79492D02*
G03X1134904Y78903I587J-590D01*
G01X1135563Y81605D02*
X1134299Y80341D01*
G01X1135873Y80216D02*
X1135149Y79492D01*
G01X1138315Y102944D02*
G03X1136196Y103822I-2120J-2120D01*
G01X1137466Y102095D02*
G03X1136195Y102622I-1272J-1271D01*
G01X1137993Y100824D02*
G03X1137466Y102095I-1798J-1D01*
G01X1139193Y100824D02*
G03X1138315Y102944I-2998J0D01*
G01X1137466Y102095D02*
G03X1136195Y102622I-1272J-1271D01*
G01X1137993Y100824D02*
G03X1137466Y102095I-1798J-1D01*
G01X1139193Y99500D02*
Y100824D01*
G01X1137993Y99499D02*
Y100824D01*
G01X1138976Y98145D02*
G03X1139193Y99500I-4106J1352D01*
G01X1137836Y98520D02*
G03X1137992Y99499I-2966J975D01*
G01X1137666Y98107D02*
G03X1137836Y98520I-2795J1392D01*
G01X1138741Y97573D02*
G03X1138976Y98145I-3871J1924D01*
G01X1137836Y98520D02*
G03X1137992Y99499I-2966J975D01*
G01X1137666Y98107D02*
G03X1137836Y98520I-2795J1392D01*
G01X1137079Y97292D02*
G03X1137666Y98108I-2208J2208D01*
G01X1130508Y74330D02*
X1118041D01*
G01X1130508Y75530D02*
X1118041D01*
G01X1133008Y75365D02*
G02X1130508Y74330I-2499J2500D01*
G01X1132159Y76214D02*
G02X1130508Y75530I-1651J1651D01*
G01X1133751Y76108D02*
X1133008Y75365D01*
G01X1132902Y76957D02*
X1132159Y76214D01*
G01X1134904Y78892D02*
G02X1133751Y76108I-3938J0D01*
G01X1133704Y78893D02*
G02X1132902Y76957I-2738J0D01*
G01X1135149Y79492D02*
G03X1134904Y78903I587J-590D01*
G01X1134299Y80341D02*
G03X1133704Y78904I1438J-1437D01*
G01X1135873Y80216D02*
X1135149Y79492D01*
G01X1135563Y81605D02*
X1134299Y80341D01*
G01X1139600Y124129D02*
Y128400D01*
G01X1140800Y124129D02*
Y128400D01*
G01X1140608Y121694D02*
G02X1139600Y124129I2435J2434D01*
G01X1141457Y122543D02*
G02X1140800Y124129I1586J1586D01*
G01X1151943Y110359D02*
X1140608Y121694D01*
G01X1152792Y111208D02*
X1141457Y122543D01*
G01X1140800Y124129D02*
Y128400D01*
G01X1139600Y124129D02*
Y128400D01*
G01X1141457Y122543D02*
G02X1140800Y124129I1586J1586D01*
G01X1140608Y121694D02*
G02X1139600Y124129I2435J2434D01*
G01X1152792Y111208D02*
X1141457Y122543D01*
G01X1151943Y110359D02*
X1140608Y121694D01*
G01X1139750Y135600D02*
Y136150D01*
G01X1140950Y135600D02*
Y136150D01*
G01X1124549Y131000D02*
X1123500D01*
G01Y132200D02*
X1124549D01*
G01X1140950Y135600D02*
Y136150D01*
G01X1139750Y135600D02*
Y136150D01*
G01X1123500Y132200D02*
X1124549D01*
G01Y131000D02*
X1123500D01*
G01X1132450D02*
X1131500D01*
G01X1132451Y132200D02*
X1131900D01*
G01X1133051Y130751D02*
G03X1132450Y131000I-601J-601D01*
G01X1133899Y131600D02*
G03X1132451Y132200I-1449J-1450D01*
G01X1133551Y130250D02*
X1133051Y130751D01*
G01X1134400Y131100D02*
X1133900Y131600D01*
G01X1134000Y129166D02*
G03X1133551Y130251I-1533J1D01*
G01X1135200Y129167D02*
G03X1134400Y131099I-2733J0D01*
G01X1134000Y116529D02*
Y129166D01*
G01X1135200Y116529D02*
Y129167D01*
G01X1135008Y114094D02*
G02X1134000Y116529I2435J2434D01*
G01X1135857Y114943D02*
G02X1135200Y116529I1586J1586D01*
G01X1132451Y132200D02*
X1131900D01*
G01X1132450Y131000D02*
X1131500D01*
G01X1133899Y131600D02*
G03X1132451Y132200I-1449J-1450D01*
G01X1133051Y130751D02*
G03X1132450Y131000I-601J-601D01*
G01X1134400Y131100D02*
X1133900Y131600D01*
G01X1133551Y130250D02*
X1133051Y130751D01*
G01X1135200Y129167D02*
G03X1134400Y131099I-2733J0D01*
G01X1134000Y129166D02*
G03X1133551Y130251I-1533J1D01*
G01X1135200Y116529D02*
Y129167D01*
G01X1134000Y116529D02*
Y129166D01*
G01X1135857Y114943D02*
G02X1135200Y116529I1586J1586D01*
G01X1135008Y114094D02*
G02X1134000Y116529I2435J2434D01*
G01X1139750Y135600D02*
Y136150D01*
G01X1140950Y135600D02*
Y136150D01*
G01X1124549Y131000D02*
X1123500D01*
G01Y132200D02*
X1124549D01*
G01X1140950Y135600D02*
Y136150D01*
G01X1139750Y135600D02*
Y136150D01*
G01X1123500Y132200D02*
X1124549D01*
G01Y131000D02*
X1123500D01*
G01X1143101Y882407D02*
Y841431D01*
G01X1143076Y832800D02*
Y831900D01*
G01X1117904Y882407D02*
Y841431D01*
G01X1119105Y882416D02*
Y841428D01*
G01X1130503Y882407D02*
Y841431D01*
G01X1131704Y882416D02*
Y841428D01*
G01X1143101Y882407D02*
Y841431D01*
G01X1119105Y882416D02*
Y841428D01*
G01X1117904Y882407D02*
Y841431D01*
G01X1131704Y882416D02*
Y841428D01*
G01X1130503Y882407D02*
Y841431D01*
G01X1117879Y832800D02*
Y831800D01*
G01X1119079Y832800D02*
Y831799D01*
G01X1130478Y831888D02*
G02X1130045Y830844I-1477J1D01*
G01X1131678Y831887D02*
G02Y831847I-2677J-20D01*
G01X1130478Y832800D02*
Y831888D01*
G01X1131678Y832800D02*
Y831887D01*
G01X1143076Y832800D02*
Y831900D01*
G01X1119079Y832800D02*
Y831799D01*
G01X1117879Y832800D02*
Y831800D01*
G01X1131678Y831887D02*
G02Y831847I-2677J-20D01*
G01X1130478Y831888D02*
G02X1130045Y830844I-1477J1D01*
G01X1131678Y832800D02*
Y831887D01*
G01X1130478Y832800D02*
Y831888D01*
G01X1117879Y832800D02*
Y831800D01*
G01X1119079Y832800D02*
Y831799D01*
G01X1130478Y831888D02*
G02X1130045Y830844I-1477J1D01*
G01X1131678Y831887D02*
G02Y831847I-2677J-20D01*
G01X1130478Y832800D02*
Y831888D01*
G01X1131678Y832800D02*
Y831887D01*
G01X1143076Y832800D02*
Y831900D01*
G01X1119079Y832800D02*
Y831799D01*
G01X1117879Y832800D02*
Y831800D01*
G01X1131678Y831887D02*
G02Y831847I-2677J-20D01*
G01X1130478Y831888D02*
G02X1130045Y830844I-1477J1D01*
G01X1131678Y832800D02*
Y831887D01*
G01X1130478Y832800D02*
Y831888D01*
G01X1143076Y832800D02*
Y831900D01*
G01X1163700Y28516D02*
Y46300D01*
G01X1164900Y28018D02*
Y45802D01*
G01X1154807Y19623D02*
X1163700Y28516D01*
G01X1156007Y19125D02*
X1164900Y28018D01*
G01X1152579Y17393D02*
X1154807Y19621D01*
G01X1153077Y16193D02*
X1156007Y19123D01*
G01X1164900Y28018D02*
Y45802D01*
G01X1163700Y28516D02*
Y46300D01*
G01X1156007Y19125D02*
X1164900Y28018D01*
G01X1154807Y19623D02*
X1163700Y28516D01*
G01X1153077Y16193D02*
X1156007Y19123D01*
G01X1152579Y17393D02*
X1154807Y19621D01*
G01X1163700Y46300D02*
X1168398Y50998D01*
G01X1164900Y45802D02*
X1167849Y48751D01*
G01X1164900Y45802D02*
X1167849Y48751D01*
G01X1163700Y46300D02*
X1168398Y50998D01*
G01X1159057Y101285D02*
Y129000D01*
G01X1160257Y101284D02*
Y129000D01*
G01X1159796Y99500D02*
G02X1159057Y101285I1784J1784D01*
G01X1160645Y100349D02*
G02X1160258Y101285I936J935D01*
G01X1168708Y90594D02*
X1159796Y99500D01*
G01X1169557Y91444D02*
X1160645Y100349D01*
G01X1172137Y89174D02*
G02X1168708Y90594I0J4850D01*
G01X1172137Y90374D02*
G02X1169557Y91444I2J3649D01*
G01X1177800Y89174D02*
X1172137D01*
G01X1177801Y90374D02*
X1172137D01*
G01X1160257Y101284D02*
Y129000D01*
G01X1159057Y101285D02*
Y129000D01*
G01X1160645Y100349D02*
G02X1160258Y101285I936J935D01*
G01X1159796Y99500D02*
G02X1159057Y101285I1784J1784D01*
G01X1169557Y91444D02*
X1160645Y100349D01*
G01X1168708Y90594D02*
X1159796Y99500D01*
G01X1172137Y90374D02*
G02X1169557Y91444I2J3649D01*
G01X1172137Y89174D02*
G02X1168708Y90594I0J4850D01*
G01X1177801Y90374D02*
X1172137D01*
G01X1177800Y89174D02*
X1172137D01*
G01X1173819Y99633D02*
G02X1173019Y97700I-2733J-1D01*
G01X1172170Y98549D02*
G03X1172619Y99633I-1084J1084D01*
G01X1173819Y102528D02*
Y99633D01*
G01X1172619D02*
Y102528D01*
G01X1173047Y104469D02*
G02X1173819Y102528I-2050J-1940D01*
G01X1172619D02*
G03X1172144Y103675I-1622J0D01*
G01X1172993Y104524D02*
G02X1173047Y104469I-1987J-2005D01*
G01X1172619Y102528D02*
G03X1172144Y103675I-1622J0D01*
G01X1172518Y104999D02*
X1172993Y104524D01*
G01X1172144Y103675D02*
X1171663Y104156D01*
G01X1172051Y106127D02*
G03X1172518Y104999I1595J0D01*
G01X1171380Y104486D02*
G02X1170851Y106104I2210J1618D01*
G01X1171663Y104156D02*
G02X1171380Y104486I2004J2005D01*
G01D02*
G02X1170851Y106104I2210J1618D01*
G01X1172051Y106127D02*
G03X1172518Y104999I1595J0D01*
G01X1171663Y104156D02*
G02X1171380Y104486I2004J2005D01*
G01X1172051Y106127D02*
G03X1172518Y104999I1595J0D01*
G01X1172144Y103675D02*
X1171663Y104156D01*
G01X1172518Y104999D02*
X1172993Y104524D01*
G01X1172619Y102528D02*
G03X1172144Y103675I-1622J0D01*
G01X1173047Y104469D02*
G02X1173819Y102528I-2050J-1940D01*
G01X1172993Y104524D02*
G02X1173047Y104469I-1987J-2005D01*
G01X1172619Y99633D02*
Y102528D01*
G01X1173819D02*
Y99633D01*
G01X1172170Y98549D02*
G03X1172619Y99633I-1084J1084D01*
G01X1173819D02*
G02X1173019Y97700I-2733J-1D01*
G01X1153100Y107567D02*
G03X1151943Y110359I-3949J-1D01*
G01X1154300Y107567D02*
G03X1152792Y111208I-5150J0D01*
G01X1153100Y95099D02*
Y107567D01*
G01X1154300Y95100D02*
Y107567D01*
G01X1152393Y93393D02*
G03X1153099Y95100I-1708J1706D01*
G01X1153242Y92544D02*
G03X1154300Y95100I-2557J2555D01*
G01X1148109Y89109D02*
X1152393Y93393D01*
G01X1148958Y88260D02*
X1153242Y92544D01*
G01X1147029Y86500D02*
G02X1148109Y89109I3689J1D01*
G01X1148229Y86500D02*
G02X1148958Y88260I2489J0D01*
G01X1147029Y84671D02*
Y86500D01*
G01X1148229Y84672D02*
Y86500D01*
G01X1146580Y83588D02*
G03X1147029Y84671I-1084J1084D01*
G01X1147429Y82739D02*
G03X1148229Y84672I-1933J1932D01*
G01X1154300Y107567D02*
G03X1152792Y111208I-5150J0D01*
G01X1153100Y107567D02*
G03X1151943Y110359I-3949J-1D01*
G01X1154300Y95100D02*
Y107567D01*
G01X1153100Y95099D02*
Y107567D01*
G01X1153242Y92544D02*
G03X1154300Y95100I-2557J2555D01*
G01X1152393Y93393D02*
G03X1153099Y95100I-1708J1706D01*
G01X1148958Y88260D02*
X1153242Y92544D01*
G01X1148109Y89109D02*
X1152393Y93393D01*
G01X1148229Y86500D02*
G02X1148958Y88260I2489J0D01*
G01X1147029Y86500D02*
G02X1148109Y89109I3689J1D01*
G01X1148229Y84672D02*
Y86500D01*
G01X1147029Y84671D02*
Y86500D01*
G01X1147429Y82739D02*
G03X1148229Y84672I-1933J1932D01*
G01X1146580Y83588D02*
G03X1147029Y84671I-1084J1084D01*
G01X1146850Y101500D02*
G03X1146320Y102782I-1813J1D01*
G01X1148051Y101500D02*
G03X1147169Y103631I-3013J1D01*
G01X1146851Y99500D02*
Y101501D01*
G01X1148051Y99500D02*
Y101500D01*
G01X1146524Y98108D02*
G03X1146851Y99500I-2795J1391D01*
G01X1147599Y97573D02*
G03X1148051Y99500I-3871J1924D01*
G01X1145937Y97292D02*
G03X1146524Y98108I-2208J2208D01*
G01X1147599Y97573D02*
G03X1148051Y99500I-3871J1924D01*
G01Y101500D02*
G03X1147169Y103631I-3013J1D01*
G01X1146850Y101500D02*
G03X1146320Y102782I-1813J1D01*
G01X1148051Y99500D02*
Y101500D01*
G01X1146851Y99500D02*
Y101501D01*
G01X1147599Y97573D02*
G03X1148051Y99500I-3871J1924D01*
G01X1146524Y98108D02*
G03X1146851Y99500I-2795J1391D01*
G01X1145937Y97292D02*
G03X1146524Y98108I-2208J2208D01*
G01X1159157Y136254D02*
Y136804D01*
G01X1160357Y136254D02*
Y136804D01*
G01Y136254D02*
Y136804D01*
G01X1159157Y136254D02*
Y136804D01*
G01X1172050Y128266D02*
Y126885D01*
G01X1170850Y113347D02*
Y128266D01*
G01Y113347D02*
Y128266D01*
G01X1172050D02*
Y126885D01*
G01X1159157Y136254D02*
Y136804D01*
G01X1160357Y136254D02*
Y136804D01*
G01Y136254D02*
Y136804D01*
G01X1159157Y136254D02*
Y136804D01*
G01X1155699Y882407D02*
Y841431D01*
G01X1156900Y882416D02*
Y841428D01*
G01X1144302Y882416D02*
Y841428D01*
G01X1156900Y882416D02*
Y841428D01*
G01X1155699Y882407D02*
Y841431D01*
G01X1155674Y832800D02*
Y831879D01*
G01X1156874Y832800D02*
Y831948D01*
G01X1144276Y832800D02*
Y831900D01*
G01X1156874Y832800D02*
Y831948D01*
G01X1155674Y832800D02*
Y831879D01*
G01X1144302Y882416D02*
Y841428D01*
G01X1144276Y832800D02*
Y831900D01*
G01Y832800D02*
Y831900D01*
G01X1155674Y832800D02*
Y831879D01*
G01X1156874Y832800D02*
Y831948D01*
G01X1144276Y832800D02*
Y831900D01*
G01X1156874Y832800D02*
Y831948D01*
G01X1155674Y832800D02*
Y831879D01*
G01X1205597Y98689D02*
Y128200D01*
G01X1206797D02*
Y98688D01*
G01X1207213Y94787D02*
G02X1205597Y98689I3901J3901D01*
G01X1206798D02*
G03X1208062Y95636I4316J-1D01*
G01X1211311Y90689D02*
X1207213Y94787D01*
G01X1208062Y95636D02*
X1212160Y91538D01*
G01X1197100Y94958D02*
Y128500D01*
G01X1198300Y94958D02*
Y128500D01*
G01X1196139Y92639D02*
G03X1197100Y94958I-2319J2320D01*
G01X1196988Y91790D02*
G03X1198300Y94958I-3169J3168D01*
G01X1191350Y87850D02*
X1196139Y92639D01*
G01X1192199Y87001D02*
X1196988Y91790D01*
G01X1190334Y85400D02*
G02X1191350Y87850I3465J-1D01*
G01X1191535Y85400D02*
G02X1192199Y87001I2264J-1D01*
G01X1190335Y85400D02*
Y85401D01*
G01X1191536Y84672D02*
Y85400D01*
G01X1190336Y84672D02*
Y85400D01*
G01X1191536Y84672D02*
Y85400D01*
G01X1189887Y83588D02*
G03X1190336Y84672I-1084J1084D01*
G01X1190736Y82739D02*
G03X1191536Y84672I-1933J1932D01*
G01X1188536Y106205D02*
Y128800D01*
G01X1189736Y106204D02*
Y128800D01*
G01X1189097Y104486D02*
G02X1188536Y106204I2343J1716D01*
G01X1190066Y105196D02*
G02X1189736Y106204I1374J1008D01*
G01X1190235Y104999D02*
G02X1190066Y105196I1205J1205D01*
G01X1189380Y104156D02*
G02X1189097Y104486I2004J2005D01*
G01X1190066Y105196D02*
G02X1189736Y106204I1374J1008D01*
G01X1190235Y104999D02*
G02X1190066Y105196I1205J1205D01*
G01X1189861Y103675D02*
X1189380Y104156D01*
G01X1190710Y104524D02*
X1190235Y104999D01*
G01X1190336Y102528D02*
G03X1189861Y103675I-1622J0D01*
G01X1190764Y104469D02*
G03X1190710Y104524I-2041J-1950D01*
G01X1191536Y102528D02*
G03X1190764Y104469I-2822J1D01*
G01X1190336Y99633D02*
Y102528D01*
G01X1191536Y99633D02*
Y102528D01*
G01X1189887Y98549D02*
G03X1190336Y99633I-1084J1084D01*
G01X1190736Y97700D02*
G03X1191536Y99633I-1933J1932D01*
G01X1179678Y106204D02*
Y128700D01*
G01X1180878D02*
Y106204D01*
G01X1180239Y104486D02*
G02X1179678Y106204I2343J1716D01*
G01X1181208Y105196D02*
G03X1181377Y104999I1374J1008D01*
G01X1180878Y106204D02*
G03X1181208Y105196I1704J0D01*
G01X1180522Y104156D02*
G02X1180239Y104486I2004J2005D01*
G01X1181208Y105196D02*
G03X1181377Y104999I1374J1008D01*
G01X1180878Y106204D02*
G03X1181208Y105196I1704J0D01*
G01X1181003Y103675D02*
X1180522Y104156D01*
G01X1181377Y104999D02*
X1181852Y104524D01*
G01X1181478Y102528D02*
G03X1181003Y103675I-1622J0D01*
G01X1181906Y104469D02*
G02X1182678Y102528I-2050J-1940D01*
G01X1181852Y104524D02*
G02X1181906Y104469I-1987J-2005D01*
G01X1181478Y99633D02*
Y102528D01*
G01X1182678D02*
Y99633D01*
G01X1181029Y98549D02*
G03X1181478Y99633I-1084J1084D01*
G01X1182678D02*
G02X1181878Y97700I-2733J-1D01*
G01X1208062Y95636D02*
X1212160Y91538D01*
G01X1211311Y90689D02*
X1207213Y94787D01*
G01X1206798Y98689D02*
G03X1208062Y95636I4316J-1D01*
G01X1207213Y94787D02*
G02X1205597Y98689I3901J3901D01*
G01X1206797Y128200D02*
Y98688D01*
G01X1205597Y98689D02*
Y128200D01*
G01X1198300Y94958D02*
Y128500D01*
G01X1197100Y94958D02*
Y128500D01*
G01X1196988Y91790D02*
G03X1198300Y94958I-3169J3168D01*
G01X1196139Y92639D02*
G03X1197100Y94958I-2319J2320D01*
G01X1192199Y87001D02*
X1196988Y91790D01*
G01X1191350Y87850D02*
X1196139Y92639D01*
G01X1191535Y85400D02*
G02X1192199Y87001I2264J-1D01*
G01X1190334Y85400D02*
G02X1191350Y87850I3465J-1D01*
G01X1191536Y84672D02*
Y85400D01*
G01X1190335D02*
Y85401D01*
G01X1190336Y84672D02*
Y85400D01*
G01X1190736Y82739D02*
G03X1191536Y84672I-1933J1932D01*
G01X1189887Y83588D02*
G03X1190336Y84672I-1084J1084D01*
G01X1189736Y106204D02*
Y128800D01*
G01X1188536Y106205D02*
Y128800D01*
G01X1190066Y105196D02*
G02X1189736Y106204I1374J1008D01*
G01X1189097Y104486D02*
G02X1188536Y106204I2343J1716D01*
G01X1189380Y104156D02*
G02X1189097Y104486I2004J2005D01*
G01X1190235Y104999D02*
G02X1190066Y105196I1205J1205D01*
G01X1189097Y104486D02*
G02X1188536Y106204I2343J1716D01*
G01X1189380Y104156D02*
G02X1189097Y104486I2004J2005D01*
G01X1190710Y104524D02*
X1190235Y104999D01*
G01X1189861Y103675D02*
X1189380Y104156D01*
G01X1190764Y104469D02*
G03X1190710Y104524I-2041J-1950D01*
G01X1190336Y102528D02*
G03X1189861Y103675I-1622J0D01*
G01X1191536Y102528D02*
G03X1190764Y104469I-2822J1D01*
G01X1190336Y102528D02*
G03X1189861Y103675I-1622J0D01*
G01X1191536Y99633D02*
Y102528D01*
G01X1190336Y99633D02*
Y102528D01*
G01X1190736Y97700D02*
G03X1191536Y99633I-1933J1932D01*
G01X1189887Y98549D02*
G03X1190336Y99633I-1084J1084D01*
G01X1182678D02*
G02X1181878Y97700I-2733J-1D01*
G01X1181029Y98549D02*
G03X1181478Y99633I-1084J1084D01*
G01X1182678Y102528D02*
Y99633D01*
G01X1181478D02*
Y102528D01*
G01X1181906Y104469D02*
G02X1182678Y102528I-2050J-1940D01*
G01X1181478D02*
G03X1181003Y103675I-1622J0D01*
G01X1181852Y104524D02*
G02X1181906Y104469I-1987J-2005D01*
G01X1181478Y102528D02*
G03X1181003Y103675I-1622J0D01*
G01X1181377Y104999D02*
X1181852Y104524D01*
G01X1181003Y103675D02*
X1180522Y104156D01*
G01X1181208Y105196D02*
G03X1181377Y104999I1374J1008D01*
G01X1180239Y104486D02*
G02X1179678Y106204I2343J1716D01*
G01X1180522Y104156D02*
G02X1180239Y104486I2004J2005D01*
G01X1180878Y106204D02*
G03X1181208Y105196I1704J0D01*
G01X1180239Y104486D02*
G02X1179678Y106204I2343J1716D01*
G01X1180522Y104156D02*
G02X1180239Y104486I2004J2005D01*
G01X1180878Y128700D02*
Y106204D01*
G01X1179678D02*
Y128700D01*
G01X1179514Y88464D02*
G03X1177800Y89174I-1714J-1714D01*
G01X1180363Y89313D02*
G03X1177801Y90374I-2562J-2563D01*
G01X1180771Y87207D02*
X1179514Y88464D01*
G01X1181620Y88056D02*
X1180363Y89313D01*
G01X1181478Y85500D02*
G03X1180771Y87207I-2414J0D01*
G01X1182678Y85500D02*
G03X1181620Y88056I-3615J1D01*
G01X1181478Y84672D02*
Y85500D01*
G01X1182678Y84672D02*
Y85500D01*
G01X1181029Y83588D02*
G03X1181478Y84672I-1084J1084D01*
G01X1181878Y82739D02*
G03X1182678Y84672I-1933J1932D01*
G01X1180363Y89313D02*
G03X1177801Y90374I-2562J-2563D01*
G01X1179514Y88464D02*
G03X1177800Y89174I-1714J-1714D01*
G01X1181620Y88056D02*
X1180363Y89313D01*
G01X1180771Y87207D02*
X1179514Y88464D01*
G01X1182678Y85500D02*
G03X1181620Y88056I-3615J1D01*
G01X1181478Y85500D02*
G03X1180771Y87207I-2414J0D01*
G01X1182678Y84672D02*
Y85500D01*
G01X1181478Y84672D02*
Y85500D01*
G01X1181878Y82739D02*
G03X1182678Y84672I-1933J1932D01*
G01X1181029Y83588D02*
G03X1181478Y84672I-1084J1084D01*
G01X1205589Y141304D02*
X1204791Y142102D01*
G01X1205589Y135600D02*
Y141304D01*
G01X1206789Y135600D02*
Y141802D01*
G01X1197250Y136768D02*
Y141150D01*
G01X1198450Y136285D02*
Y141150D01*
G01X1188685Y135648D02*
Y136198D01*
G01X1189885Y135648D02*
Y136198D01*
G01X1179911Y136895D02*
Y140777D01*
G01X1181111Y136412D02*
Y140777D01*
G01X1205589Y141304D02*
X1204791Y142102D01*
G01X1206789Y135600D02*
Y141802D01*
G01X1205589Y135600D02*
Y141304D01*
G01X1198450Y136285D02*
Y141150D01*
G01X1197250Y136768D02*
Y141150D01*
G01X1189885Y135648D02*
Y136198D01*
G01X1188685Y135648D02*
Y136198D01*
G01X1181111Y136412D02*
Y140777D01*
G01X1179911Y136895D02*
Y140777D01*
G01X1205589Y141304D02*
X1204791Y142102D01*
G01X1205589Y135600D02*
Y141304D01*
G01X1206789Y135600D02*
Y141802D01*
G01X1197250Y136768D02*
Y141150D01*
G01X1198450Y136285D02*
Y141150D01*
G01X1188685Y135648D02*
Y136198D01*
G01X1189885Y135648D02*
Y136198D01*
G01X1179911Y136895D02*
Y140777D01*
G01X1181111Y136412D02*
Y140777D01*
G01X1205589Y141304D02*
X1204791Y142102D01*
G01X1206789Y135600D02*
Y141802D01*
G01X1205589Y135600D02*
Y141304D01*
G01X1198450Y136285D02*
Y141150D01*
G01X1197250Y136768D02*
Y141150D01*
G01X1189885Y135648D02*
Y136198D01*
G01X1188685Y135648D02*
Y136198D01*
G01X1181111Y136412D02*
Y140777D01*
G01X1179911Y136895D02*
Y140777D01*
G01X1204791Y142102D02*
Y155730D01*
G01X1205991Y142600D02*
Y155730D01*
G01X1206789Y141802D02*
X1205991Y142600D01*
G01D02*
Y155730D01*
G01X1204791Y142102D02*
Y155730D01*
G01X1206789Y141802D02*
X1205991Y142600D01*
G01X1204791Y142102D02*
Y155730D01*
G01X1205991Y142600D02*
Y155730D01*
G01X1206789Y141802D02*
X1205991Y142600D01*
G01D02*
Y155730D01*
G01X1204791Y142102D02*
Y155730D01*
G01X1206789Y141802D02*
X1205991Y142600D01*
G01X1190345Y882407D02*
Y841431D01*
G01X1191546Y882416D02*
Y841428D01*
G01X1178948Y882416D02*
Y841428D01*
G01X1177747Y882407D02*
Y841431D01*
G01X1191546Y882416D02*
Y841428D01*
G01X1190345Y882407D02*
Y841431D01*
G01X1190320Y832800D02*
Y831820D01*
G01X1191520Y832800D02*
Y831820D01*
G01X1178922Y831700D02*
G02Y831686I-2224J-7D01*
G01X1177722Y831700D02*
G02X1177422Y830976I-1024J0D01*
G01X1178922Y832800D02*
Y831700D01*
G01X1177722Y832800D02*
Y831700D01*
G01X1191520Y832800D02*
Y831820D01*
G01X1190320Y832800D02*
Y831820D01*
G01X1177747Y882407D02*
Y841431D01*
G01X1178948Y882416D02*
Y841428D01*
G01X1177722Y831700D02*
G02X1177422Y830976I-1024J0D01*
G01X1178922Y831700D02*
G02Y831686I-2224J-7D01*
G01X1177722Y832800D02*
Y831700D01*
G01X1178922Y832800D02*
Y831700D01*
G01X1177722D02*
G02X1177422Y830976I-1024J0D01*
G01X1178922Y831700D02*
G02Y831686I-2224J-7D01*
G01X1177722Y832800D02*
Y831700D01*
G01X1178922Y832800D02*
Y831700D01*
G01X1190320Y832800D02*
Y831820D01*
G01X1191520Y832800D02*
Y831820D01*
G01X1178922Y831700D02*
G02Y831686I-2224J-7D01*
G01X1177722Y831700D02*
G02X1177422Y830976I-1024J0D01*
G01X1178922Y832800D02*
Y831700D01*
G01X1177722Y832800D02*
Y831700D01*
G01X1191520Y832800D02*
Y831820D01*
G01X1190320Y832800D02*
Y831820D01*
G01X1222985Y106205D02*
Y128500D01*
G01X1224185Y106204D02*
Y128500D01*
G01X1223546Y104486D02*
G02X1222985Y106204I2343J1716D01*
G01X1224515Y105196D02*
G02X1224185Y106204I1374J1008D01*
G01X1224684Y104999D02*
G02X1224515Y105196I1205J1205D01*
G01X1223829Y104156D02*
G02X1223546Y104486I2004J2005D01*
G01X1224515Y105196D02*
G02X1224185Y106204I1374J1008D01*
G01X1224684Y104999D02*
G02X1224515Y105196I1205J1205D01*
G01X1224310Y103675D02*
X1223829Y104156D01*
G01X1225159Y104524D02*
X1224684Y104999D01*
G01X1224785Y102528D02*
G03X1224310Y103675I-1622J0D01*
G01X1225213Y104469D02*
G03X1225159Y104524I-2041J-1950D01*
G01X1225985Y102528D02*
G03X1225213Y104469I-2822J1D01*
G01X1224785Y99633D02*
Y102528D01*
G01X1225985Y99633D02*
Y102528D01*
G01X1224336Y98549D02*
G03X1224785Y99633I-1084J1084D01*
G01X1225185Y97700D02*
G03X1225985Y99633I-1933J1932D01*
G01X1240600Y96585D02*
Y128200D01*
G01X1241800Y96585D02*
Y128200D01*
G01X1239830Y94728D02*
G03X1240600Y96585I-1856J1858D01*
G01X1240679Y93879D02*
G03X1241800Y96585I-2706J2706D01*
G01X1234651Y89549D02*
X1239830Y94728D01*
G01X1235500Y88700D02*
X1240679Y93879D01*
G01X1233643Y87115D02*
G02X1234651Y89549I3443J0D01*
G01X1234843Y87114D02*
G02X1235500Y88700I2243J0D01*
G01X1233643Y84672D02*
Y87115D01*
G01X1234843Y84672D02*
Y87114D01*
G01X1233194Y83588D02*
G03X1233643Y84672I-1084J1084D01*
G01X1234043Y82739D02*
G03X1234843Y84672I-1933J1932D01*
G01X1231843Y106205D02*
Y128300D01*
G01X1233043Y106204D02*
Y128300D01*
G01X1232404Y104486D02*
G02X1231843Y106204I2343J1716D01*
G01X1233373Y105196D02*
G02X1233043Y106204I1374J1008D01*
G01X1233542Y104999D02*
G02X1233373Y105196I1205J1205D01*
G01X1232687Y104156D02*
G02X1232404Y104486I2004J2005D01*
G01X1233373Y105196D02*
G02X1233043Y106204I1374J1008D01*
G01X1233542Y104999D02*
G02X1233373Y105196I1205J1205D01*
G01X1233168Y103675D02*
X1232687Y104156D01*
G01X1234017Y104524D02*
X1233542Y104999D01*
G01X1233643Y102528D02*
G03X1233168Y103675I-1622J0D01*
G01X1234071Y104469D02*
G03X1234017Y104524I-2041J-1950D01*
G01X1234843Y102528D02*
G03X1234071Y104469I-2822J1D01*
G01X1233643Y99633D02*
Y102528D01*
G01X1234843Y99633D02*
Y102528D01*
G01X1233194Y98549D02*
G03X1233643Y99633I-1084J1084D01*
G01X1234043Y97700D02*
G03X1234843Y99633I-1933J1932D01*
G01X1224185Y106204D02*
Y128500D01*
G01X1222985Y106205D02*
Y128500D01*
G01X1224515Y105196D02*
G02X1224185Y106204I1374J1008D01*
G01X1223546Y104486D02*
G02X1222985Y106204I2343J1716D01*
G01X1223829Y104156D02*
G02X1223546Y104486I2004J2005D01*
G01X1224684Y104999D02*
G02X1224515Y105196I1205J1205D01*
G01X1223546Y104486D02*
G02X1222985Y106204I2343J1716D01*
G01X1223829Y104156D02*
G02X1223546Y104486I2004J2005D01*
G01X1225159Y104524D02*
X1224684Y104999D01*
G01X1224310Y103675D02*
X1223829Y104156D01*
G01X1225213Y104469D02*
G03X1225159Y104524I-2041J-1950D01*
G01X1224785Y102528D02*
G03X1224310Y103675I-1622J0D01*
G01X1225985Y102528D02*
G03X1225213Y104469I-2822J1D01*
G01X1224785Y102528D02*
G03X1224310Y103675I-1622J0D01*
G01X1225985Y99633D02*
Y102528D01*
G01X1224785Y99633D02*
Y102528D01*
G01X1225185Y97700D02*
G03X1225985Y99633I-1933J1932D01*
G01X1224336Y98549D02*
G03X1224785Y99633I-1084J1084D01*
G01X1241800Y96585D02*
Y128200D01*
G01X1240600Y96585D02*
Y128200D01*
G01X1240679Y93879D02*
G03X1241800Y96585I-2706J2706D01*
G01X1239830Y94728D02*
G03X1240600Y96585I-1856J1858D01*
G01X1235500Y88700D02*
X1240679Y93879D01*
G01X1234651Y89549D02*
X1239830Y94728D01*
G01X1234843Y87114D02*
G02X1235500Y88700I2243J0D01*
G01X1233643Y87115D02*
G02X1234651Y89549I3443J0D01*
G01X1234843Y84672D02*
Y87114D01*
G01X1233643Y84672D02*
Y87115D01*
G01X1234043Y82739D02*
G03X1234843Y84672I-1933J1932D01*
G01X1233194Y83588D02*
G03X1233643Y84672I-1084J1084D01*
G01X1233043Y106204D02*
Y128300D01*
G01X1231843Y106205D02*
Y128300D01*
G01X1233373Y105196D02*
G02X1233043Y106204I1374J1008D01*
G01X1232404Y104486D02*
G02X1231843Y106204I2343J1716D01*
G01X1232687Y104156D02*
G02X1232404Y104486I2004J2005D01*
G01X1233542Y104999D02*
G02X1233373Y105196I1205J1205D01*
G01X1232404Y104486D02*
G02X1231843Y106204I2343J1716D01*
G01X1232687Y104156D02*
G02X1232404Y104486I2004J2005D01*
G01X1234017Y104524D02*
X1233542Y104999D01*
G01X1233168Y103675D02*
X1232687Y104156D01*
G01X1234071Y104469D02*
G03X1234017Y104524I-2041J-1950D01*
G01X1233643Y102528D02*
G03X1233168Y103675I-1622J0D01*
G01X1234843Y102528D02*
G03X1234071Y104469I-2822J1D01*
G01X1233643Y102528D02*
G03X1233168Y103675I-1622J0D01*
G01X1234843Y99633D02*
Y102528D01*
G01X1233643Y99633D02*
Y102528D01*
G01X1234043Y97700D02*
G03X1234843Y99633I-1933J1932D01*
G01X1233194Y98549D02*
G03X1233643Y99633I-1084J1084D01*
G01X1215361Y106122D02*
Y127900D01*
G01X1214161Y127899D02*
Y106123D01*
G01X1215826Y104999D02*
G02X1215361Y106122I1123J1123D01*
G01X1214161Y106123D02*
G03X1214977Y104150I2788J-2D01*
G01X1216301Y104524D02*
X1215826Y104999D01*
G01X1214977Y104150D02*
X1215452Y103675D01*
G01X1217127Y102530D02*
G03X1216301Y104524I-2820J0D01*
G01X1215452Y103675D02*
G02X1215927Y102528I-1147J-1147D01*
G01X1217127Y99633D02*
Y102530D01*
G01X1215927Y102528D02*
Y99633D01*
G01X1216327Y97700D02*
G03X1217127Y99633I-1933J1932D01*
G01X1215927D02*
G02X1215478Y98549I-1533J0D01*
G01X1215927Y99633D02*
G02X1215478Y98549I-1533J0D01*
G01X1216327Y97700D02*
G03X1217127Y99633I-1933J1932D01*
G01X1215927Y102528D02*
Y99633D01*
G01X1217127D02*
Y102530D01*
G01X1215452Y103675D02*
G02X1215927Y102528I-1147J-1147D01*
G01X1217127Y102530D02*
G03X1216301Y104524I-2820J0D01*
G01X1214977Y104150D02*
X1215452Y103675D01*
G01X1216301Y104524D02*
X1215826Y104999D01*
G01X1214161Y106123D02*
G03X1214977Y104150I2788J-2D01*
G01X1215826Y104999D02*
G02X1215361Y106122I1123J1123D01*
G01X1214161Y127899D02*
Y106123D01*
G01X1215361Y106122D02*
Y127900D01*
G01X1215510Y88950D02*
G02X1211311Y90689I0J5939D01*
G01X1212160Y91538D02*
G03X1215510Y90150I3351J3351D01*
G01X1222335Y88950D02*
X1215510D01*
G01Y90150D02*
X1222335D01*
G01X1224785Y86500D02*
G03X1222335Y88950I-2450J0D01*
G01Y90150D02*
G02X1225985Y86500I0J-3650D01*
G01X1224785Y84672D02*
Y86500D01*
G01X1225985D02*
Y84672D01*
G01X1224623Y83987D02*
G03X1224785Y84672I-1367J685D01*
G01X1225985D02*
G02X1225697Y83451I-2734J0D01*
G01X1225985Y84672D02*
G02X1225697Y83451I-2734J0D01*
G01X1224623Y83987D02*
G03X1224785Y84672I-1367J685D01*
G01X1225985Y86500D02*
Y84672D01*
G01X1224785D02*
Y86500D01*
G01X1222335Y90150D02*
G02X1225985Y86500I0J-3650D01*
G01X1224785D02*
G03X1222335Y88950I-2450J0D01*
G01X1215510Y90150D02*
X1222335D01*
G01Y88950D02*
X1215510D01*
G01X1212160Y91538D02*
G03X1215510Y90150I3351J3351D01*
G01Y88950D02*
G02X1211311Y90689I0J5939D01*
G01X1223198Y135709D02*
Y136259D01*
G01X1224398Y135709D02*
Y136259D01*
G01X1240750Y135600D02*
Y136150D01*
G01X1241950Y135600D02*
Y136150D01*
G01X1232059Y136880D02*
Y140762D01*
G01X1233259Y136397D02*
Y140762D01*
G01X1224398Y135709D02*
Y136259D01*
G01X1223198Y135709D02*
Y136259D01*
G01X1241950Y135600D02*
Y136150D01*
G01X1240750Y135600D02*
Y136150D01*
G01X1233259Y136397D02*
Y140762D01*
G01X1232059Y136880D02*
Y140762D01*
G01X1240750Y135600D02*
Y136150D01*
G01X1241950Y135600D02*
Y136150D01*
G01Y135600D02*
Y136150D01*
G01X1240750Y135600D02*
Y136150D01*
G01X1223198Y135709D02*
Y136259D01*
G01X1224398Y135709D02*
Y136259D01*
G01X1232059Y136880D02*
Y140762D01*
G01X1233259Y136397D02*
Y140762D01*
G01X1224398Y135709D02*
Y136259D01*
G01X1223198Y135709D02*
Y136259D01*
G01X1233259Y136397D02*
Y140762D01*
G01X1232059Y136880D02*
Y140762D01*
G01X1221842Y882407D02*
Y841431D01*
G01X1223043Y882416D02*
Y841426D01*
G01X1234440Y882407D02*
Y841431D01*
G01X1235641Y882416D02*
Y841428D01*
G01X1223043Y882416D02*
Y841426D01*
G01X1221842Y882407D02*
Y841431D01*
G01X1235641Y882416D02*
Y841428D01*
G01X1234440Y882407D02*
Y841431D01*
G01X1221817Y832800D02*
Y831817D01*
G01X1223017Y832800D02*
Y831817D01*
G01X1234415Y832800D02*
Y831800D01*
G01X1235615Y832800D02*
Y831844D01*
G01X1223017Y832800D02*
Y831817D01*
G01X1221817Y832800D02*
Y831817D01*
G01X1235615Y832800D02*
Y831844D01*
G01X1234415Y832800D02*
Y831800D01*
G01X1221817Y832800D02*
Y831817D01*
G01X1223017Y832800D02*
Y831817D01*
G01X1234415Y832800D02*
Y831800D01*
G01X1235615Y832800D02*
Y831844D01*
G01X1223017Y832800D02*
Y831817D01*
G01X1221817Y832800D02*
Y831817D01*
G01X1235615Y832800D02*
Y831844D01*
G01X1234415Y832800D02*
Y831800D01*
G01X1258955Y53838D02*
X1258084Y52967D01*
G01X1259804Y52989D02*
X1259633Y52818D01*
G01X1259619Y55444D02*
G02X1258955Y53838I-2272J-1D01*
G01X1260820Y55444D02*
G02X1259804Y52989I-3472J-1D01*
G01X1259620Y56526D02*
Y55443D01*
G01X1260820Y56526D02*
Y55444D01*
G01X1259378Y57109D02*
G02X1259620Y56526I-583J-584D01*
G01X1260227Y57958D02*
G02X1260820Y56526I-1433J-1432D01*
G01X1245862Y70625D02*
X1259378Y57109D01*
G01X1247062Y71123D02*
X1260227Y57958D01*
G01X1245862Y113316D02*
Y70625D01*
G01X1247062Y113814D02*
Y71123D01*
G01Y113814D02*
Y71123D01*
G01X1259804Y52989D02*
X1259633Y52818D01*
G01X1258955Y53838D02*
X1258084Y52967D01*
G01X1260820Y55444D02*
G02X1259804Y52989I-3472J-1D01*
G01X1259619Y55444D02*
G02X1258955Y53838I-2272J-1D01*
G01X1260820Y56526D02*
Y55444D01*
G01X1259620Y56526D02*
Y55443D01*
G01X1260227Y57958D02*
G02X1260820Y56526I-1433J-1432D01*
G01X1259378Y57109D02*
G02X1259620Y56526I-583J-584D01*
G01X1247062Y71123D02*
X1260227Y57958D01*
G01X1245862Y70625D02*
X1259378Y57109D01*
G01X1247062Y113814D02*
Y71123D01*
G01X1245862Y113316D02*
Y70625D01*
G01X1276950Y84672D02*
G02X1276501Y83588I-1533J0D01*
G01X1278150Y84672D02*
G02X1277350Y82739I-2733J-1D01*
G01X1276950Y86800D02*
Y84672D01*
G01X1278150Y86801D02*
Y84672D01*
G01X1278044Y89445D02*
G03X1276950Y86800I2647J-2643D01*
G01X1278894Y88596D02*
G03X1278151Y86800I1797J-1795D01*
G01X1292458Y103858D02*
X1278044Y89445D01*
G01X1276950Y99633D02*
G02X1276501Y98549I-1533J0D01*
G01X1278150Y99633D02*
G02X1277350Y97700I-2733J-1D01*
G01X1276950Y102528D02*
Y99633D01*
G01X1278150Y102528D02*
Y99633D01*
G01X1276475Y103675D02*
G02X1276950Y102528I-1147J-1147D01*
G01X1277378Y104469D02*
G02X1278150Y102528I-2050J-1940D01*
G01X1277324Y104524D02*
G02X1277378Y104469I-1987J-2005D01*
G01X1275994Y104156D02*
X1276475Y103675D01*
G01X1276849Y104999D02*
X1277324Y104524D01*
G01X1275711Y104486D02*
G03X1275994Y104156I2287J1675D01*
G01X1276350Y106204D02*
G03X1276849Y104999I1704J0D01*
G01X1275150Y106204D02*
G03X1275711Y104486I2904J-2D01*
G01X1276350Y106204D02*
G03X1276849Y104999I1704J0D01*
G01X1275150Y108056D02*
Y106204D01*
G01X1276350Y108056D02*
Y106204D01*
G01X1267642Y98549D02*
G03X1267606Y98512I1445J-1441D01*
G01X1268492Y97700D02*
G03X1268246Y97106I594J-594D01*
G01X1268091Y99633D02*
G02X1267642Y98549I-1532J0D01*
G01X1269292Y99633D02*
G02X1268492Y97700I-2733J-1D01*
G01X1268092Y107996D02*
Y99632D01*
G01X1269292Y107996D02*
Y99633D01*
G01X1268092Y84672D02*
G02X1267643Y83588I-1533J0D01*
G01X1269292Y84672D02*
G02X1268492Y82739I-2733J-1D01*
G01X1268092Y85800D02*
Y84672D01*
G01X1269292Y85800D02*
Y84672D01*
G01X1264717Y89175D02*
G02X1268092Y85800I0J-3375D01*
G01X1264717Y90375D02*
G02X1269292Y85800I0J-4575D01*
G01X1258367Y89175D02*
X1264717D01*
G01X1258367Y90375D02*
X1264717D01*
G01X1255654Y90298D02*
G03X1258367Y89175I2712J2714D01*
G01X1256503Y91147D02*
G03X1258367Y90375I1864J1864D01*
G01X1251977Y93975D02*
X1255654Y90298D01*
G01X1252826Y94824D02*
X1256503Y91147D01*
G01X1250900Y96576D02*
G03X1251977Y93975I3677J-1D01*
G01X1252100Y96576D02*
G03X1252826Y94824I2477J0D01*
G01X1250900Y110553D02*
Y96576D01*
G01X1252100Y110553D02*
Y96576D01*
G01X1278150Y84672D02*
G02X1277350Y82739I-2733J-1D01*
G01X1276950Y84672D02*
G02X1276501Y83588I-1533J0D01*
G01X1278150Y86801D02*
Y84672D01*
G01X1276950Y86800D02*
Y84672D01*
G01X1278894Y88596D02*
G03X1278151Y86800I1797J-1795D01*
G01X1278044Y89445D02*
G03X1276950Y86800I2647J-2643D01*
G01X1292458Y103858D02*
X1278044Y89445D01*
G01X1278150Y99633D02*
G02X1277350Y97700I-2733J-1D01*
G01X1276950Y99633D02*
G02X1276501Y98549I-1533J0D01*
G01X1278150Y102528D02*
Y99633D01*
G01X1276950Y102528D02*
Y99633D01*
G01X1277378Y104469D02*
G02X1278150Y102528I-2050J-1940D01*
G01X1276475Y103675D02*
G02X1276950Y102528I-1147J-1147D01*
G01X1277324Y104524D02*
G02X1277378Y104469I-1987J-2005D01*
G01X1276475Y103675D02*
G02X1276950Y102528I-1147J-1147D01*
G01X1276849Y104999D02*
X1277324Y104524D01*
G01X1275994Y104156D02*
X1276475Y103675D01*
G01X1276350Y106204D02*
G03X1276849Y104999I1704J0D01*
G01X1275711Y104486D02*
G03X1275994Y104156I2287J1675D01*
G01X1275150Y106204D02*
G03X1275711Y104486I2904J-2D01*
G01X1276350Y108056D02*
Y106204D01*
G01X1275150Y108056D02*
Y106204D01*
G01X1268492Y97700D02*
G03X1268246Y97106I594J-594D01*
G01X1267642Y98549D02*
G03X1267606Y98512I1445J-1441D01*
G01X1269292Y99633D02*
G02X1268492Y97700I-2733J-1D01*
G01X1268091Y99633D02*
G02X1267642Y98549I-1532J0D01*
G01X1269292Y107996D02*
Y99633D01*
G01X1268092Y107996D02*
Y99632D01*
G01X1269292Y84672D02*
G02X1268492Y82739I-2733J-1D01*
G01X1268092Y84672D02*
G02X1267643Y83588I-1533J0D01*
G01X1269292Y85800D02*
Y84672D01*
G01X1268092Y85800D02*
Y84672D01*
G01X1264717Y90375D02*
G02X1269292Y85800I0J-4575D01*
G01X1264717Y89175D02*
G02X1268092Y85800I0J-3375D01*
G01X1258367Y90375D02*
X1264717D01*
G01X1258367Y89175D02*
X1264717D01*
G01X1256503Y91147D02*
G03X1258367Y90375I1864J1864D01*
G01X1255654Y90298D02*
G03X1258367Y89175I2712J2714D01*
G01X1252826Y94824D02*
X1256503Y91147D01*
G01X1251977Y93975D02*
X1255654Y90298D01*
G01X1252100Y96576D02*
G03X1252826Y94824I2477J0D01*
G01X1250900Y96576D02*
G03X1251977Y93975I3677J-1D01*
G01X1252100Y110553D02*
Y96576D01*
G01X1250900Y110553D02*
Y96576D01*
G01X1260434Y99633D02*
G02X1259634Y97700I-2733J-1D01*
G01X1259234Y99633D02*
G02X1258785Y98549I-1533J0D01*
G01X1260434Y102528D02*
Y99633D01*
G01X1259234Y102528D02*
Y99633D01*
G01X1259662Y104469D02*
G02X1260434Y102528I-2050J-1940D01*
G01X1258759Y103675D02*
G02X1259234Y102528I-1147J-1147D01*
G01X1259608Y104524D02*
G02X1259662Y104469I-1987J-2005D01*
G01X1258759Y103675D02*
G02X1259234Y102528I-1147J-1147D01*
G01X1259133Y104999D02*
X1259608Y104524D01*
G01X1258278Y104156D02*
X1258759Y103675D01*
G01X1258964Y105196D02*
G03X1259133Y104999I1374J1008D01*
G01X1257995Y104486D02*
G03X1258278Y104156I2287J1675D01*
G01X1257553Y105380D02*
G03X1257995Y104486I2786J821D01*
G01X1258705Y105720D02*
G03X1258964Y105196I1634J482D01*
G01X1257995Y104486D02*
G03X1258278Y104156I2287J1675D01*
G01X1257553Y105380D02*
G03X1257995Y104486I2786J821D01*
G01X1257539Y105428D02*
G03X1257553Y105380I2795J789D01*
G01X1258682Y105873D02*
G03X1258704Y105720I543J0D01*
G01X1257482Y105872D02*
G03X1257539Y105428I1744J-2D01*
G01X1258682Y109889D02*
Y105873D01*
G01X1257482Y109889D02*
Y105872D01*
G01X1259234Y99633D02*
G02X1258785Y98549I-1533J0D01*
G01X1260434Y99633D02*
G02X1259634Y97700I-2733J-1D01*
G01X1259234Y102528D02*
Y99633D01*
G01X1260434Y102528D02*
Y99633D01*
G01X1258759Y103675D02*
G02X1259234Y102528I-1147J-1147D01*
G01X1259662Y104469D02*
G02X1260434Y102528I-2050J-1940D01*
G01X1259608Y104524D02*
G02X1259662Y104469I-1987J-2005D01*
G01X1258278Y104156D02*
X1258759Y103675D01*
G01X1259133Y104999D02*
X1259608Y104524D01*
G01X1257995Y104486D02*
G03X1258278Y104156I2287J1675D01*
G01X1258964Y105196D02*
G03X1259133Y104999I1374J1008D01*
G01X1258705Y105720D02*
G03X1258964Y105196I1634J482D01*
G01X1257553Y105380D02*
G03X1257995Y104486I2786J821D01*
G01X1258964Y105196D02*
G03X1259133Y104999I1374J1008D01*
G01X1258705Y105720D02*
G03X1258964Y105196I1634J482D01*
G01X1257539Y105428D02*
G03X1257553Y105380I2795J789D01*
G01X1258705Y105720D02*
G03X1258964Y105196I1634J482D01*
G01X1257482Y105872D02*
G03X1257539Y105428I1744J-2D01*
G01X1258682Y105873D02*
G03X1258704Y105720I543J0D01*
G01X1257482Y109889D02*
Y105872D01*
G01X1258682Y109889D02*
Y105873D01*
G01X1275115Y135422D02*
Y135972D01*
G01X1276315Y135422D02*
Y135972D01*
G01X1259794Y136687D02*
Y144069D01*
G01X1260994Y136204D02*
Y144069D01*
G01X1276315Y135422D02*
Y135972D01*
G01X1275115Y135422D02*
Y135972D01*
G01X1260994Y136204D02*
Y144069D01*
G01X1259794Y136687D02*
Y144069D01*
G01X1276063Y110261D02*
G03X1275150Y108056I2204J-2204D01*
G01X1276912Y109412D02*
G03X1276350Y108056I1355J-1356D01*
G01X1282977Y117175D02*
X1276063Y110261D01*
G01X1283826Y116326D02*
X1276912Y109412D01*
G01X1269360Y111058D02*
G03X1268092Y107996I3061J-3061D01*
G01X1270209Y110209D02*
G03X1269292Y107996I2212J-2213D01*
G01X1273512Y115210D02*
X1269360Y111058D01*
G01X1274361Y114361D02*
X1270209Y110209D01*
G01X1274900Y118560D02*
G02X1273512Y115210I-4737J0D01*
G01X1276100Y118559D02*
G02X1274361Y114361I-5937J0D01*
G01X1274900Y127700D02*
Y118560D01*
G01X1276100Y127700D02*
Y118559D01*
G01X1252081Y113405D02*
G03X1250900Y110553I2851J-2851D01*
G01X1252930Y112556D02*
G03X1252100Y110553I2002J-2003D01*
G01X1259004Y120328D02*
X1252081Y113405D01*
G01X1259853Y119479D02*
X1252930Y112556D01*
G01X1259596Y121755D02*
G02X1259004Y120328I-2018J1D01*
G01X1260796Y121755D02*
G02X1259853Y119479I-3218J0D01*
G01X1259596Y127944D02*
Y121755D01*
G01X1260796Y127944D02*
Y121755D01*
G01X1276912Y109412D02*
G03X1276350Y108056I1355J-1356D01*
G01X1276063Y110261D02*
G03X1275150Y108056I2204J-2204D01*
G01X1283826Y116326D02*
X1276912Y109412D01*
G01X1282977Y117175D02*
X1276063Y110261D01*
G01X1270209Y110209D02*
G03X1269292Y107996I2212J-2213D01*
G01X1269360Y111058D02*
G03X1268092Y107996I3061J-3061D01*
G01X1274361Y114361D02*
X1270209Y110209D01*
G01X1273512Y115210D02*
X1269360Y111058D01*
G01X1276100Y118559D02*
G02X1274361Y114361I-5937J0D01*
G01X1274900Y118560D02*
G02X1273512Y115210I-4737J0D01*
G01X1276100Y127700D02*
Y118559D01*
G01X1274900Y127700D02*
Y118560D01*
G01X1252930Y112556D02*
G03X1252100Y110553I2002J-2003D01*
G01X1252081Y113405D02*
G03X1250900Y110553I2851J-2851D01*
G01X1259853Y119479D02*
X1252930Y112556D01*
G01X1259004Y120328D02*
X1252081Y113405D01*
G01X1260796Y121755D02*
G02X1259853Y119479I-3218J0D01*
G01X1259596Y121755D02*
G02X1259004Y120328I-2018J1D01*
G01X1260796Y127944D02*
Y121755D01*
G01X1259596Y127944D02*
Y121755D01*
G01X1258840Y110270D02*
G03X1258682Y109889I380J-381D01*
G01X1257991Y111119D02*
G03X1257482Y109889I1230J-1229D01*
G01X1268091Y119521D02*
X1258840Y110270D01*
G01X1267242Y120370D02*
X1257991Y111119D01*
G01X1268601Y120751D02*
G02X1268091Y119521I-1740J1D01*
G01X1267401Y120752D02*
G02X1267242Y120370I-540J0D01*
G01X1268601Y127902D02*
Y120751D01*
G01X1267401Y127899D02*
Y120752D01*
G01X1257991Y111119D02*
G03X1257482Y109889I1230J-1229D01*
G01X1258840Y110270D02*
G03X1258682Y109889I380J-381D01*
G01X1267242Y120370D02*
X1257991Y111119D01*
G01X1268091Y119521D02*
X1258840Y110270D01*
G01X1267401Y120752D02*
G02X1267242Y120370I-540J0D01*
G01X1268601Y120751D02*
G02X1268091Y119521I-1740J1D01*
G01X1267401Y127899D02*
Y120752D01*
G01X1268601Y127902D02*
Y120751D01*
G01X1245861Y114311D02*
Y113317D01*
G01X1251099Y119549D02*
X1245861Y114311D01*
G01X1252299Y119051D02*
X1247062Y113814D01*
G01X1251099Y127700D02*
Y119549D01*
G01X1252299Y127700D02*
Y119051D01*
G01X1245861Y114311D02*
Y113317D01*
G01X1252299Y119051D02*
X1247062Y113814D01*
G01X1251099Y119549D02*
X1245861Y114311D01*
G01X1252299Y127700D02*
Y119051D01*
G01X1251099Y127700D02*
Y119549D01*
G01X1275115Y135422D02*
Y135972D01*
G01X1276315Y135422D02*
Y135972D01*
G01X1259794Y136687D02*
Y144069D01*
G01X1260994Y136204D02*
Y144069D01*
G01X1276315Y135422D02*
Y135972D01*
G01X1275115Y135422D02*
Y135972D01*
G01X1260994Y136204D02*
Y144069D01*
G01X1259794Y136687D02*
Y144069D01*
G01X1247039Y882407D02*
Y841431D01*
G01X1248240Y882416D02*
Y841426D01*
G01X1259637Y882407D02*
Y841431D01*
G01X1260838Y882416D02*
Y841428D01*
G01X1272235Y882407D02*
Y841431D01*
G01X1273436Y882416D02*
Y841428D01*
G01X1248240Y882416D02*
Y841426D01*
G01X1247039Y882407D02*
Y841431D01*
G01X1260838Y882416D02*
Y841428D01*
G01X1259637Y882407D02*
Y841431D01*
G01X1273436Y882416D02*
Y841428D01*
G01X1272235Y882407D02*
Y841431D01*
G01X1247014Y832800D02*
Y831914D01*
G01X1248214Y832800D02*
Y831914D01*
G01X1259612Y832800D02*
Y831912D01*
G01X1260812Y832800D02*
Y831947D01*
G01X1272210Y832800D02*
Y831800D01*
G01X1273410Y832800D02*
Y831844D01*
G01X1248214Y832800D02*
Y831914D01*
G01X1247014Y832800D02*
Y831914D01*
G01X1260812Y832800D02*
Y831947D01*
G01X1259612Y832800D02*
Y831912D01*
G01X1273410Y832800D02*
Y831844D01*
G01X1272210Y832800D02*
Y831800D01*
G01X1247014Y832800D02*
Y831914D01*
G01X1248214Y832800D02*
Y831914D01*
G01X1259612Y832800D02*
Y831912D01*
G01X1260812Y832800D02*
Y831947D01*
G01X1272210Y832800D02*
Y831800D01*
G01X1273410Y832800D02*
Y831844D01*
G01X1248214Y832800D02*
Y831914D01*
G01X1247014Y832800D02*
Y831914D01*
G01X1260812Y832800D02*
Y831947D01*
G01X1259612Y832800D02*
Y831912D01*
G01X1273410Y832800D02*
Y831844D01*
G01X1272210Y832800D02*
Y831800D01*
G01X1293307Y103009D02*
X1278894Y88596D01*
G01X1293716Y106893D02*
G02X1292458Y103858I-4292J1D01*
G01X1294916Y106893D02*
G02X1293307Y103009I-5492J0D01*
G01X1293716Y127551D02*
Y106893D01*
G01X1294916Y127551D02*
Y106893D01*
G01X1293307Y103009D02*
X1278894Y88596D01*
G01X1294916Y106893D02*
G02X1293307Y103009I-5492J0D01*
G01X1293716Y106893D02*
G02X1292458Y103858I-4292J1D01*
G01X1294916Y127551D02*
Y106893D01*
G01X1293716Y127551D02*
Y106893D01*
G01X1293867Y135227D02*
Y135777D01*
G01X1295067Y135227D02*
Y135777D01*
G01X1284393Y136498D02*
Y139880D01*
G01X1285593Y136015D02*
Y139880D01*
G01X1295067Y135227D02*
Y135777D01*
G01X1293867Y135227D02*
Y135777D01*
G01X1285593Y136015D02*
Y139880D01*
G01X1284393Y136498D02*
Y139880D01*
G01X1284249Y120244D02*
G02X1282977Y117175I-4340J1D01*
G01X1285449Y120244D02*
G02X1283826Y116326I-5541J0D01*
G01X1284249Y127836D02*
Y120244D01*
G01X1285449Y127836D02*
Y120244D01*
G01D02*
G02X1283826Y116326I-5541J0D01*
G01X1284249Y120244D02*
G02X1282977Y117175I-4340J1D01*
G01X1285449Y127836D02*
Y120244D01*
G01X1284249Y127836D02*
Y120244D01*
G01X1293867Y135227D02*
Y135777D01*
G01X1295067Y135227D02*
Y135777D01*
G01X1284393Y136498D02*
Y139880D01*
G01X1285593Y136015D02*
Y139880D01*
G01X1295067Y135227D02*
Y135777D01*
G01X1293867Y135227D02*
Y135777D01*
G01X1285593Y136015D02*
Y139880D01*
G01X1284393Y136498D02*
Y139880D01*
G01X1284833Y882407D02*
Y841431D01*
G01X1286034Y882416D02*
Y841428D01*
G01X1310031Y882407D02*
Y841431D01*
G01X1311232Y882416D02*
Y841426D01*
G01X1286034Y882416D02*
Y841428D01*
G01X1284833Y882407D02*
Y841431D01*
G01X1311232Y882416D02*
Y841426D01*
G01X1310031Y882407D02*
Y841431D01*
G01X1284808Y831800D02*
G02X1284437Y830906I-1265J1D01*
G01X1286008Y831799D02*
G02Y831748I-2465J-25D01*
G01X1284808Y832800D02*
Y831800D01*
G01X1286008Y832800D02*
Y831799D01*
G01X1310006Y832800D02*
Y831900D01*
G01X1311206Y832800D02*
Y831949D01*
G01X1286008Y831799D02*
G02Y831748I-2465J-25D01*
G01X1284808Y831800D02*
G02X1284437Y830906I-1265J1D01*
G01X1286008Y832800D02*
Y831799D01*
G01X1284808Y832800D02*
Y831800D01*
G01X1311206Y832800D02*
Y831949D01*
G01X1310006Y832800D02*
Y831900D01*
G01X1284808Y831800D02*
G02X1284437Y830906I-1265J1D01*
G01X1286008Y831799D02*
G02Y831748I-2465J-25D01*
G01X1284808Y832800D02*
Y831800D01*
G01X1286008Y832800D02*
Y831799D01*
G01X1310006Y832800D02*
Y831900D01*
G01X1311206Y832800D02*
Y831949D01*
G01X1286008Y831799D02*
G02Y831748I-2465J-25D01*
G01X1284808Y831800D02*
G02X1284437Y830906I-1265J1D01*
G01X1286008Y832800D02*
Y831799D01*
G01X1284808Y832800D02*
Y831800D01*
G01X1311206Y832800D02*
Y831949D01*
G01X1310006Y832800D02*
Y831900D01*
G01X1322629Y882407D02*
Y841431D01*
G01X1323830Y882416D02*
Y841428D01*
G01X1335227Y882407D02*
Y841431D01*
G01X1336428Y882416D02*
Y841428D01*
G01X1323830Y882416D02*
Y841428D01*
G01X1322629Y882407D02*
Y841431D01*
G01X1336428Y882416D02*
Y841428D01*
G01X1335227Y882407D02*
Y841431D01*
G01X1322604Y831700D02*
G02X1322304Y830976I-1024J0D01*
G01X1323804Y831700D02*
G02Y831692I-2224J-4D01*
G01X1322604Y832800D02*
Y831700D01*
G01X1323804Y832800D02*
Y831700D01*
G01X1335202Y832800D02*
Y832046D01*
G01X1336402Y832800D02*
Y832046D01*
G01X1323804Y831700D02*
G02Y831692I-2224J-4D01*
G01X1322604Y831700D02*
G02X1322304Y830976I-1024J0D01*
G01X1323804Y832800D02*
Y831700D01*
G01X1322604Y832800D02*
Y831700D01*
G01X1336402Y832800D02*
Y832046D01*
G01X1335202Y832800D02*
Y832046D01*
G01X1322604Y831700D02*
G02X1322304Y830976I-1024J0D01*
G01X1323804Y831700D02*
G02Y831692I-2224J-4D01*
G01X1322604Y832800D02*
Y831700D01*
G01X1323804Y832800D02*
Y831700D01*
G01X1335202Y832800D02*
Y832046D01*
G01X1336402Y832800D02*
Y832046D01*
G01X1323804Y831700D02*
G02Y831692I-2224J-4D01*
G01X1322604Y831700D02*
G02X1322304Y830976I-1024J0D01*
G01X1323804Y832800D02*
Y831700D01*
G01X1322604Y832800D02*
Y831700D01*
G01X1336402Y832800D02*
Y832046D01*
G01X1335202Y832800D02*
Y832046D01*
G01X1347825Y882407D02*
Y841431D01*
G01X1349026Y882416D02*
Y841428D01*
G01Y882416D02*
Y841428D01*
G01X1347825Y882407D02*
Y841431D01*
G01X1347800Y832559D02*
Y831800D01*
G01X1349000Y832558D02*
Y831800D01*
G01Y832558D02*
Y831800D01*
G01X1347800Y832559D02*
Y831800D01*
G01Y832559D02*
Y831800D01*
G01X1349000Y832558D02*
Y831800D01*
G01Y832558D02*
Y831800D01*
G01X1347800Y832559D02*
Y831800D01*
M02*
